G04 ================== begin FILE IDENTIFICATION RECORD ==================*
G04 Layout Name:  t6mg_pdb_a_v02_0109_1330.brd*
G04 Film Name:    in1*
G04 File Format:  Gerber RS274X*
G04 File Origin:  Cadence Allegro 16.3-S038*
G04 Origin Date:  Mon Jan 13 14:11:52 2014*
G04 *
G04 Layer:  DRAWING FORMAT/TITLE_BLOCK*
G04 Layer:  VIA CLASS/IN1*
G04 Layer:  PIN/IN1*
G04 Layer:  MANUFACTURING/PHOTOPLOT_OUTLINE*
G04 Layer:  ETCH/IN1*
G04 Layer:  DRAWING FORMAT/TITLE_DATA_IN1*
G04 *
G04 Offset:    (0.00 0.00)*
G04 Mirror:    No*
G04 Mode:      Positive*
G04 Rotation:  0*
G04 FullContactRelief:  No*
G04 UndefLineWidth:     6.00*
G04 ================== end FILE IDENTIFICATION RECORD ====================*
%FSLAX25Y25*MOIN*%
%IR0*IPPOS*OFA0.00000B0.00000*MIA0B0*SFA1.00000B1.00000*%
%ADD10C,.02*%
%ADD12C,.04*%
%ADD11C,.063*%
%ADD16C,.046*%
%ADD15C,.064*%
%ADD14C,.055*%
%ADD13C,.077*%
%ADD17C,.025*%
%ADD18C,.018*%
%ADD19C,.005*%
%ADD20C,.006*%
%ADD29C,.03004*%
%ADD30C,.05004*%
%ADD28C,.06204*%
%ADD27C,.07304*%
%ADD36C,.05604*%
%ADD35C,.07404*%
%ADD34C,.06504*%
%ADD32C,.08704*%
%ADD23C,.08409*%
%ADD33C,.10304*%
%ADD31C,.10504*%
%ADD37C,.40406*%
%ADD24C,.24506*%
%ADD21C,.16406*%
%ADD26C,.13266*%
%ADD25C,.35606*%
%ADD22C,.15806*%
G75*
%LPD*%
G75*
G36*
G01X104331Y2004D02*
G02X100429Y5906I0J3902D01*
G01Y9843D01*
G03X92520Y17752I-7909J0D01*
G01X5906D01*
G02X2004Y21654I0J3902D01*
G01Y2064961D01*
G02X5905Y2068862I3901J0D01*
G01X92520D01*
G03X100429Y2076772I0J7909D01*
G01Y2080709D01*
G02X104331Y2084610I3902J-1D01*
G01X397638D01*
G02X403508Y2078740I0J-5870D01*
G01Y7874D01*
G02X397638Y2004I-5870J0D01*
G01X104331D01*
G37*
%LPC*%
G75*
G36*
G01X104331Y3997D02*
X104330D01*
G02X102422Y5906I0J1908D01*
G01Y9843D01*
G03X92520Y19745I-9903J-1D01*
G01X91602D01*
Y19746D01*
X5906D01*
Y19745D01*
X5905D01*
G02X3998Y21711I1J1908D01*
G01Y2064961D01*
G02X4556Y2066310I1908J1D01*
G02X5964Y2066868I1349J-1349D01*
G01X92520D01*
G03X99522Y2069769I-1J9903D01*
G03X102422Y2076772I-7003J7002D01*
G01Y2080709D01*
G02X104330Y2082617I1908J0D01*
G01X104331D01*
Y2082616D01*
X397638D01*
G02X401514Y2078740I0J-3876D01*
G01Y1915551D01*
X401515Y1915541D01*
Y1915529D01*
X401514D01*
Y7874D01*
G02X397638Y3998I-3876J0D01*
G01X104331D01*
Y3997D01*
G37*
%LPD*%
G75*
G36*
G01X363694Y332350D02*
Y332587D01*
X363526Y332754D01*
X363497Y332799D01*
G03X363051Y333245I-1262J-816D01*
G01X363006Y333274D01*
X359936Y336344D01*
Y343485D01*
X347820Y355602D01*
X308616D01*
X303348Y360870D01*
X124603D01*
X122528Y362944D01*
G02X122754Y363719I991J131D01*
G03X123350Y367495I-2834J2382D01*
G03X122064Y369120I-3430J-1393D01*
G03X117084Y368482I-2144J-3018D01*
G02X115318Y369093I-766J643D01*
G01Y373111D01*
G02X117084Y373722I1000J-32D01*
G03Y378482I2836J2380D01*
G02X115318Y379093I-766J643D01*
G01Y383111D01*
G02X117084Y383722I1000J-32D01*
G03Y388482I2836J2380D01*
G02X115318Y389093I-766J643D01*
G01Y393990D01*
X115027Y394281D01*
Y394696D01*
X115217Y394886D01*
X115270Y394918D01*
G03X115383Y394993I-773J1288D01*
G01X115468Y395056D01*
X115672Y395101D01*
X116125Y395011D01*
X116487Y394712D01*
X116535Y394604D01*
G03X118182Y392833I3386J1497D01*
G03X120385Y392429I1738J3269D01*
G03X121598Y392802I-465J3673D01*
G03X122126Y393129I-1678J3300D01*
G03X122992Y394036I-2206J2973D01*
G03X120047Y399802I-3072J2066D01*
G03X119116Y399716I-128J-3700D01*
G03X117413Y398826I804J-3614D01*
G02X115750Y399574I-663J748D01*
G01Y402630D01*
G02X117413Y403378I1000J0D01*
G03Y408826I2507J2724D01*
G02X115750Y409574I-663J748D01*
G01Y412003D01*
X117066Y413319D01*
X117448Y413339D01*
X117597Y413219D01*
G03X123595Y415655I2323J2883D01*
G01Y415660D01*
G03X123616Y416310I-3675J444D01*
G03X123537Y416892I-3696J-205D01*
G03X122634Y418620I-3617J-790D01*
G03X122122Y419078I-2713J-2518D01*
G03X121588Y419407I-2202J-2976D01*
G03X118434Y419493I-1668J-3305D01*
G02X117054Y420386I-380J925D01*
G01Y421818D01*
G02X118434Y422711I1000J-32D01*
G03Y429493I1486J3391D01*
G02X117054Y430386I-380J925D01*
G01Y431818D01*
G02X118434Y432711I1000J-32D01*
G03X122824Y438398I1487J3390D01*
G03X118976Y439682I-2904J-2296D01*
G03X117836Y439162I944J-3579D01*
G02X117054Y439575I-282J413D01*
G01Y440138D01*
X115750Y441442D01*
Y443577D01*
G02X116184Y444073I500J0D01*
G02X117070Y443739I132J-991D01*
G03Y448465I2850J2363D01*
G02X116184Y448131I-754J657D01*
G02X115750Y448627I66J496D01*
G01Y453577D01*
G02X116184Y454073I500J0D01*
G02X117070Y453739I132J-991D01*
G03Y458465I2850J2363D01*
G02X116184Y458131I-754J657D01*
G02X115750Y458627I66J496D01*
G01Y463577D01*
G02X116184Y464073I500J0D01*
G02X117070Y463739I132J-991D01*
G03Y468465I2850J2363D01*
G02X116184Y468131I-754J657D01*
G02X115750Y468627I66J496D01*
G01Y473577D01*
G02X116184Y474073I500J0D01*
G02X117070Y473739I132J-991D01*
G03Y478465I2850J2363D01*
G02X116184Y478131I-754J657D01*
G02X115750Y478627I66J496D01*
G01Y483577D01*
G02X116184Y484073I500J0D01*
G02X117070Y483739I132J-991D01*
G03Y488465I2850J2363D01*
G02X116184Y488131I-754J657D01*
G02X115750Y488627I66J496D01*
G01Y493577D01*
G02X116184Y494073I500J0D01*
G02X117070Y493739I132J-991D01*
G03Y498465I2850J2363D01*
G02X116184Y498131I-754J657D01*
G02X115750Y498627I66J496D01*
G01Y503577D01*
G02X116184Y504073I500J0D01*
G02X117070Y503739I132J-991D01*
G03Y508465I2850J2363D01*
G02X116184Y508131I-754J657D01*
G02X115750Y508627I66J496D01*
G01Y513577D01*
G02X116184Y514073I500J0D01*
G02X117070Y513739I132J-991D01*
G03Y518465I2850J2363D01*
G02X116184Y518131I-754J657D01*
G02X115750Y518627I66J496D01*
G01Y523577D01*
G02X116184Y524073I500J0D01*
G02X117070Y523739I132J-991D01*
G03Y528465I2850J2363D01*
G02X116184Y528131I-754J657D01*
G02X115750Y528627I66J496D01*
G01Y533577D01*
G02X116184Y534073I500J0D01*
G02X117070Y533739I132J-991D01*
G03Y538465I2850J2363D01*
G02X116184Y538131I-754J657D01*
G02X115750Y538627I66J496D01*
G01Y543577D01*
G02X116184Y544073I500J0D01*
G02X117070Y543739I132J-991D01*
G03Y548465I2850J2363D01*
G02X116184Y548131I-754J657D01*
G02X115750Y548627I66J496D01*
G01Y553577D01*
G02X116184Y554073I500J0D01*
G02X117070Y553739I132J-991D01*
G03Y558465I2850J2363D01*
G02X116184Y558131I-754J657D01*
G02X115750Y558627I66J496D01*
G01Y687009D01*
X113580Y689179D01*
G02X113680Y690680I707J707D01*
G01X229474D01*
X302364Y617790D01*
Y579585D01*
X318815Y563134D01*
X320155D01*
X325300Y557990D01*
G02X325446Y557637I-354J-353D01*
G01Y539849D01*
X328426Y536868D01*
Y454469D01*
X319522Y445565D01*
Y423591D01*
X319511Y423539D01*
G03Y422911I1469J-314D01*
G01X319522Y422859D01*
Y402661D01*
X326400Y395784D01*
G02X326546Y395431I-354J-353D01*
G01Y372749D01*
X338102Y361192D01*
X362296D01*
X367974Y366871D01*
Y371101D01*
X367768Y371307D01*
Y371585D01*
X363397Y375956D01*
X363119D01*
X362857Y376218D01*
G02Y376926I353J354D01*
G01X362940Y377009D01*
X363052Y377046D01*
G03X364794Y378735I-887J2658D01*
G03X364940Y380094I-2629J970D01*
G03X364800Y380659I-2775J-388D01*
G03X364628Y381041I-2634J-956D01*
G03X364611Y381073I-2483J-1298D01*
G03X363651Y382080I-2445J-1369D01*
G02X363416Y382504I265J424D01*
G01Y384563D01*
X360818Y387162D01*
X358658Y389322D01*
X356229D01*
X343576Y401975D01*
X343541Y402099D01*
G03X342512Y403128I-1444J-415D01*
G01X342388Y403163D01*
X335086Y410465D01*
Y447808D01*
X337844Y450566D01*
Y540771D01*
X335009Y543606D01*
G02X334862Y543938I352J355D01*
G01Y546217D01*
G02X336191Y547078I998J-84D01*
G03X336258Y547054I978J2625D01*
G03X339631Y548373I908J2651D01*
G03X339687Y548482I-2464J1335D01*
G02X341259Y548759I891J-455D01*
G01X341414Y548604D01*
X341565Y548454D01*
X341772D01*
X342064Y548162D01*
Y547954D01*
G02X341655Y547462I-500J0D01*
G03X342677I511J-2757D01*
G02X342268Y547954I91J492D01*
G02X342768Y548454I500J0D01*
G01X344367D01*
G02X344791Y548219I0J-500D01*
G03X347738Y546962I2375J1486D01*
G03X349080Y547658I-571J2743D01*
G03X349897Y549074I-1913J2048D01*
G02X350384Y549461I487J-113D01*
G01X350592D01*
X350884Y549169D01*
Y547485D01*
G02X350654Y547064I-500J0D01*
G03X353678I1512J-2359D01*
G02X353448Y547485I270J421D01*
G01Y548960D01*
G02X354432Y549086I500J0D01*
G01X354435Y549074D01*
X354438Y549063D01*
X354440Y549056D01*
G03X354841Y548141I2726J649D01*
G03X358855Y547469I2325J1564D01*
G03X359954Y549421I-1689J2236D01*
G03X354500Y550571I-2788J286D01*
G01X354464Y550460D01*
X354213Y550202D01*
G02X353502Y550197I-358J349D01*
G01X352941Y550757D01*
G02X353344Y552162I858J514D01*
G03X354267Y556559I-1178J2543D01*
G03X353653Y557080I-2101J-1854D01*
G02X353418Y557504I265J424D01*
G01Y557758D01*
X351893Y559283D01*
G02X351746Y559615I352J355D01*
G01Y561208D01*
X337563Y575392D01*
G02X337609Y576850I707J707D01*
G03X335489Y578970I-992J1128D01*
G02X334031Y578924I-751J661D01*
G01X330707Y582248D01*
G02X330687Y583642I707J707D01*
G03X328563Y585766I-1051J1073D01*
G02X327169Y585786I-687J727D01*
G01X325149Y587806D01*
G02X325002Y588138I352J355D01*
G01Y588315D01*
X325065Y588428D01*
G03Y589882I-1314J727D01*
G01X325002Y589995D01*
Y613905D01*
X322994Y615914D01*
Y618288D01*
X271358Y669924D01*
G02X271283Y671255I707J707D01*
G03X269172Y673366I-1174J937D01*
G02X267841Y673441I-624J782D01*
G01X234327Y706954D01*
X232122D01*
G02X231806Y707101I40J499D01*
G01X230575Y708332D01*
X121858D01*
G02X121829Y708334I20J500D01*
G01X120703Y709460D01*
G02X121286Y710693I952J304D01*
G03X121645Y710858I-1364J3441D01*
G03X123564Y714788I-1725J3276D01*
G03X122043Y717167I-3644J-654D01*
G03X121682Y717390I-2123J-3033D01*
G03X116307Y714942I-1762J-3256D01*
G01X116275Y714800D01*
X116173Y714698D01*
G02X115465I-354J353D01*
G01X112054Y718109D01*
Y766629D01*
G02X112949Y767624I1000J1D01*
G03Y770620I-113J1498D01*
G02X112054Y771615I105J994D01*
G01Y791875D01*
G02X113286Y792848I1000J0D01*
G03X113685Y795795I412J1445D01*
G02X113253Y796037I-4J500D01*
G03X112407Y796697I-1286J-776D01*
G01X112250Y796745D01*
X112054Y797010D01*
Y887877D01*
X110335Y889596D01*
G02X110188Y889919I352J355D01*
G01Y896316D01*
X39388Y967116D01*
Y972838D01*
X38000Y974227D01*
X36877Y975350D01*
X36871D01*
X36579Y975642D01*
Y976990D01*
G02X35655Y978284I32J1000D01*
G03X34806Y980988I-2392J734D01*
G01X34720Y981166D01*
Y986911D01*
G02X34866Y987264I500J0D01*
G01X51324Y1003721D01*
Y1010335D01*
X59083Y1018095D01*
G02X59755Y1017945I131J-992D01*
G03X61854Y1017924I1060J1081D01*
G01X61920Y1017987D01*
X62243Y1018122D01*
X62568Y1017999D01*
X62631Y1017948D01*
G03X65073Y1019252I946J1167D01*
G03X63823Y1020597I-1496J-137D01*
G02X63280Y1022291I164J986D01*
G01X67793Y1026804D01*
X166610D01*
X168127Y1025288D01*
X174055D01*
G02X174430Y1024321I-611J-793D01*
G03X177010Y1022988I1467J-324D01*
G03X177278Y1024591I-1112J1010D01*
G01X177238Y1024685D01*
Y1024788D01*
G02X177738Y1025288I500J0D01*
G01X178297D01*
X182365Y1021220D01*
X182389D01*
G02X182852Y1020908I0J-500D01*
G01X183014Y1020509D01*
X182903Y1020166D01*
X182865Y1020109D01*
G03X185371I1253J-829D01*
G01X185333Y1020166D01*
X185222Y1020509D01*
X185384Y1020908D01*
G02X185847Y1021220I463J-188D01*
G01X186523D01*
G02X186898Y1020596I-612J-792D01*
G03X189872I1487J214D01*
G02X190247Y1021220I987J-168D01*
G01X254301D01*
G02X254654Y1021074I0J-500D01*
G01X306854Y968873D01*
Y927432D01*
X325060Y909225D01*
Y851258D01*
X330216Y846103D01*
G02X330362Y845750I-354J-353D01*
G01Y798435D01*
G02X330216Y798082I-500J0D01*
G01X326066Y793933D01*
Y758386D01*
X326051Y758316D01*
X326047Y758291D01*
G03X326039Y758247I1473J-291D01*
G03Y757794I1485J-227D01*
G03X326065Y757662I1485J224D01*
G03X326210Y757293I1458J360D01*
G01X326272Y757180D01*
Y722798D01*
X335890Y713180D01*
X357411D01*
X361068Y716837D01*
G02X361479Y716981I354J-353D01*
G01X361536Y716974D01*
X361561Y716968D01*
G03X363882Y721921I606J2736D01*
G01X363688Y722316D01*
Y727094D01*
X363880Y727484D01*
X363966Y727556D01*
Y727557D01*
G03X363653Y732080I-1797J2148D01*
G02X363418Y732504I265J424D01*
G01Y734537D01*
X356961Y740994D01*
X356694D01*
X345588Y752100D01*
X345553Y752224D01*
G03X344924Y753071I-1444J-415D01*
G01X344879Y753100D01*
X340688Y757291D01*
Y850584D01*
X335410Y855862D01*
Y896637D01*
G02X336430Y897001I793J-611D01*
G03Y902409I735J2704D01*
G02X335410Y902773I-227J975D01*
G01Y906637D01*
G02X336430Y907001I793J-611D01*
G03X337748Y906964I735J2704D01*
G03X339133Y907710I-583J2741D01*
G03X339561Y908252I-1968J1994D01*
G03X339778Y908694I-2397J1451D01*
G01X339816Y908792D01*
X339890Y908867D01*
G02X340598I354J-353D01*
G01X340878Y908587D01*
Y907482D01*
G02X340649Y907061I-500J-1D01*
G03X339493Y905549I1516J-2357D01*
G03X339686Y903398I2672J-844D01*
G01X339687Y903397D01*
G03X340142Y902766I2478J1307D01*
G03X340450Y902489I2022J1939D01*
G03X342317Y901907I1715J2216D01*
G03X343264Y902127I-151J2798D01*
G03X344727Y903569I-1099J2578D01*
G01Y903570D01*
X344785Y903700D01*
X345250Y904018D01*
X345626Y903972D01*
X345878Y903688D01*
Y902482D01*
G02X345649Y902061I-500J-1D01*
G03X344493Y900549I1516J-2357D01*
G03X344686Y898398I2672J-844D01*
G01X344687Y898397D01*
G03X345142Y897766I2478J1307D01*
G03X346647Y896951I2023J1939D01*
G03X347785Y896972I518J2754D01*
G03X349727Y898570I-620J2733D01*
G03X348622Y902099I-2562J1135D01*
G01X348510Y902167D01*
X348382Y902395D01*
Y905596D01*
X347946Y906032D01*
Y906661D01*
X348248Y907116D01*
X348373Y907176D01*
G03X346744Y912476I-1207J2529D01*
G02X346315Y912617I-75J494D01*
G01X330186Y928745D01*
G02X330040Y929098I354J353D01*
G01Y932893D01*
X330051Y932945D01*
G03X329897Y933989I-1468J317D01*
G01X329834Y934102D01*
Y943668D01*
X330174Y944008D01*
G02X330880Y944009I354J-354D01*
G01X331018Y943871D01*
X331027Y943677D01*
G03X332582Y942245I1500J69D01*
G03X333932Y943214I-55J1501D01*
G03X333946Y943253I-1406J527D01*
G03X333822Y944507I-1419J493D01*
G03X333145Y945115I-1295J-761D01*
G02X332884Y946718I446J895D01*
G01X332924Y946758D01*
X332972Y946807D01*
Y947429D01*
X333064Y947644D01*
Y948216D01*
X332972Y948308D01*
Y951107D01*
X329834Y954245D01*
Y966553D01*
X282425Y1013963D01*
G02X282330Y1015266I707J707D01*
G03X280228Y1017368I-1206J896D01*
G02X278925Y1017463I-596J802D01*
G01X254961Y1041427D01*
Y1043545D01*
X256980Y1045564D01*
X345067D01*
X345869Y1046365D01*
X345993Y1046400D01*
G03X346116Y1046442I-423J1441D01*
G03X346255Y1046503I-533J1404D01*
G03X347022Y1047429I-677J1341D01*
G01X347057Y1047553D01*
X366846Y1067343D01*
Y1072153D01*
X363043Y1075956D01*
X362765D01*
G02X362265Y1076456I0J500D01*
G01Y1076638D01*
X362496Y1076915D01*
X362674Y1076948D01*
G03X364794Y1078735I-510J2756D01*
G03X364941Y1080088I-2629J970D01*
G03X364627Y1081043I-2776J-383D01*
G03X364590Y1081108I-2453J-1353D01*
G03X363651Y1082080I-2425J-1403D01*
G02X363416Y1082504I265J424D01*
G01Y1085280D01*
X354064Y1094632D01*
X334690D01*
X331530Y1091472D01*
X331132Y1091075D01*
X330124Y1090067D01*
Y1072714D01*
X314136Y1056726D01*
X87858D01*
X84242Y1060342D01*
X84207Y1060466D01*
G03X83178Y1061495I-1444J-415D01*
G01X83054Y1061530D01*
X52779Y1091804D01*
X44443D01*
G02X44166Y1091933I63J497D01*
G01X35876Y1100223D01*
G02X35736Y1100657I353J354D01*
G03X35745Y1100715I-2468J413D01*
G03X31882Y1103146I-2478J347D01*
G03X33650Y1098589I1385J-2084D01*
G01X33674Y1098593D01*
X33726Y1098596D01*
G02X34109Y1098450I29J-499D01*
G01X41443Y1091116D01*
G02X40794Y1089434I-732J-684D01*
G01X35061D01*
G02X34706Y1089581I-1J500D01*
G01X34665Y1089623D01*
X34631Y1089657D01*
G02X34747Y1091170I707J707D01*
G03X31249Y1094668I-1480J2018D01*
G02X29736Y1094552I-806J591D01*
G01X28002Y1096286D01*
G02X27862Y1096720I353J354D01*
G03X25798Y1094656I-2469J405D01*
G02X26232Y1094516I80J-493D01*
G01X31903Y1088845D01*
G02X31787Y1087332I-707J-707D01*
G03X31249Y1086794I1480J-2018D01*
G02X29736Y1086678I-806J591D01*
G01X28002Y1088412D01*
G02X27862Y1088846I353J354D01*
G03X25400Y1091753I-2469J405D01*
G03X23901Y1091260I-8J-2502D01*
G03X23010Y1088487I1492J-2009D01*
G03X23867Y1087268I2382J764D01*
G03X24936Y1086791I1526J1983D01*
G03X25779Y1086778I460J2460D01*
G01X25804Y1086782D01*
X25960Y1086791D01*
X26159Y1086715D01*
X26235Y1086639D01*
X28564Y1084310D01*
G02X27915Y1082628I-732J-684D01*
G01X27832D01*
G02X27425Y1082836I-1J500D01*
G01Y1082837D01*
G03X27080Y1083225I-2032J-1460D01*
G03X22993Y1080669I-1687J-1848D01*
G02X22023Y1079424I-969J-245D01*
G01X19274D01*
X18074Y1080624D01*
X18000Y1080856D01*
X18021Y1080976D01*
G03X18025Y1081002I-2471J393D01*
G03X17909Y1082214I-2474J375D01*
G03X16015Y1083836I-2358J-837D01*
G03X13533Y1082857I-464J-2459D01*
G02X12020Y1082741I-806J591D01*
G01X10286Y1084475D01*
G02X10146Y1084909I353J354D01*
G03X6482Y1087512I-2469J405D01*
G03X6456Y1087498I1173J-2209D01*
G02X5000Y1088388I-456J890D01*
G01Y1090114D01*
G02X6456Y1091004I1000J0D01*
G03Y1095372I1221J2184D01*
G02X5000Y1096262I-456J890D01*
G01Y1097988D01*
G02X6456Y1098878I1000J0D01*
G03Y1103246I1221J2184D01*
G02X5000Y1104136I-456J890D01*
G01Y1105862D01*
G02X6456Y1106752I1000J0D01*
G03Y1111120I1221J2184D01*
G02X5000Y1112010I-456J890D01*
G01Y1113736D01*
G02X6456Y1114626I1000J0D01*
G03Y1118994I1221J2184D01*
G02X5000Y1119884I-456J890D01*
G01Y1121610D01*
G02X6456Y1122500I1000J0D01*
G03X9217Y1122712I1221J2184D01*
G03X9709Y1123224I-1540J1972D01*
G02X10115Y1123432I406J-292D01*
G01X12481D01*
G02X13357Y1121951I0J-1000D01*
G03X13124Y1120139I2194J-1203D01*
G03X14746Y1118379I2427J609D01*
G03X15899Y1118270I806J2369D01*
G03X15913Y1118273I-517J2446D01*
G01X15945Y1118278D01*
X16012Y1118282D01*
G02X16393Y1118136I27J-499D01*
G01X17825Y1116704D01*
X19552Y1114978D01*
X22153D01*
G02X23028Y1113690I-84J-998D01*
G03X27758I2365J-817D01*
G02X28633Y1114978I959J290D01*
G01X29141D01*
X29546Y1115382D01*
X29718Y1115554D01*
G02X31204Y1115394I672J-741D01*
G03X32156Y1114568I2063J1416D01*
G03X35658Y1117548I1111J2242D01*
G02X36613Y1118842I955J294D01*
G01X37500D01*
X39474Y1120816D01*
X83191D01*
X113828Y1151453D01*
Y1371000D01*
X119462Y1376634D01*
X169486D01*
X169508Y1376612D01*
X174892D01*
X177949Y1373555D01*
X178513Y1372992D01*
X182993Y1368512D01*
X233634D01*
G02X233911Y1368383I-63J-497D01*
G01X293717Y1308577D01*
G02X293474Y1306984I-707J-707D01*
G03X295483Y1304975I659J-1350D01*
G02X297076Y1305218I886J-464D01*
G01X320499Y1281795D01*
X320534Y1281671D01*
G03X321163Y1280824I1444J415D01*
G01X321208Y1280795D01*
X335708Y1266295D01*
Y1262364D01*
G02X335505Y1261961I-500J-1D01*
G03X335273Y1261771I1656J-2259D01*
G03X335115Y1261616I1881J-2076D01*
G03X335047Y1261540I2054J-1906D01*
G03X334552Y1260718I2118J-1835D01*
G03X334400Y1259249I2613J-1013D01*
G03X339151Y1257728I2765J456D01*
G02X340460Y1257822I709J-706D01*
G01X340912Y1257370D01*
Y1257362D01*
X340536Y1256986D01*
X340505Y1256963D01*
G03X341977Y1251909I1660J-2258D01*
G01X342165Y1251896D01*
X342656Y1251403D01*
Y1248007D01*
X342158Y1247507D01*
G03X339817Y1243175I7J-2802D01*
G03X340933Y1242188I2348J1530D01*
G03X344760Y1243647I1232J2517D01*
G02X346393Y1243977I926J-377D01*
G01X346452Y1243919D01*
X346917Y1243454D01*
X349366D01*
G02X349790Y1243219I0J-500D01*
G03Y1246191I2375J1486D01*
G02X349366Y1245956I-424J265D01*
G01X347954D01*
X347730Y1246180D01*
G02Y1246887I354J353D01*
G01X347821Y1246978D01*
X347945Y1247014D01*
G03X348651Y1252080I-780J2691D01*
G02X348416Y1252504I265J424D01*
G01Y1254102D01*
G02X348916Y1254602I500J0D01*
G02X349408Y1254193I0J-500D01*
G03X353879Y1252488I2756J511D01*
G03X354948Y1254378I-1714J2217D01*
G03X354926Y1255183I-2783J327D01*
G03X354913Y1255255I-2764J-462D01*
G03X354414Y1256377I-2748J-550D01*
G03X354065Y1256765I-2249J-1672D01*
G03X353651Y1257080I-1896J-2063D01*
G02X353416Y1257505I265J424D01*
G01Y1259109D01*
G02X353916Y1259609I500J0D01*
G01X354097D01*
X354374Y1259379D01*
X354407Y1259200D01*
G03X354490Y1258870I2755J517D01*
G03X355370Y1257553I2675J835D01*
G03X355495Y1257455I1791J2155D01*
G03X359967Y1259751I1670J2250D01*
G03X359963Y1259857I-2802J-53D01*
G03X359962Y1259868I-2790J-248D01*
G03X357867Y1262418I-2797J-163D01*
G03X357842Y1262424I-666J-2721D01*
G03X356163Y1262322I-677J-2719D01*
G03X356108Y1262300I1013J-2612D01*
G03X355139Y1261641I1057J-2595D01*
G02X353416Y1262300I-723J691D01*
G01Y1268999D01*
X339526Y1282890D01*
X339491Y1283014D01*
G03X338462Y1284043I-1444J-415D01*
G01X338338Y1284078D01*
X329754Y1292662D01*
X320710D01*
G02X320357Y1292808I0J500D01*
G01X237620Y1375546D01*
X187625D01*
X176359Y1386812D01*
G02X175368Y1387944I0J1000D01*
G01X183006Y1395582D01*
X353589D01*
X371950Y1377221D01*
Y1366290D01*
X373390Y1364850D01*
X373419Y1364805D01*
G03X375496Y1366882I1262J815D01*
G01X375451Y1366911D01*
X374864Y1367498D01*
Y1378429D01*
X354797Y1398496D01*
X344328D01*
G02X344228Y1399998I607J795D01*
G01X344421Y1400191D01*
X344545Y1400226D01*
G03X345574Y1401255I-415J1444D01*
G01X345609Y1401379D01*
X347559Y1403329D01*
G02X349235Y1402870I707J-707D01*
G03X351063Y1404698I1455J373D01*
G02X350604Y1406374I248J969D01*
G01X361067Y1416837D01*
G02X361478Y1416981I354J-353D01*
G01X361535Y1416974D01*
X361560Y1416968D01*
G03X363015Y1422375I606J2736D01*
G03X362847Y1422423I-853J-2669D01*
G01X362679Y1422465D01*
X362469Y1422735D01*
Y1426675D01*
X362679Y1426945D01*
X362847Y1426987D01*
G03X364650Y1428410I-682J2718D01*
G03X364966Y1429628I-2485J1295D01*
G03X364954Y1429979I-2801J80D01*
G03X364542Y1431189I-2789J-274D01*
G03X364292Y1431529I-2376J-1485D01*
G03X363651Y1432080I-2126J-1825D01*
G02X363416Y1432504I265J424D01*
G01Y1435877D01*
X360264Y1439029D01*
X359868Y1439426D01*
X357644Y1441650D01*
X334463D01*
X334280Y1441467D01*
G02X332572Y1442110I-709J706D01*
G01Y1564014D01*
X333765Y1565207D01*
X333889Y1565242D01*
G03X334918Y1566271I-415J1444D01*
G01X334953Y1566395D01*
X340385Y1571827D01*
G02X342015Y1571503I707J-707D01*
G03X343979Y1573467I1387J577D01*
G02X343655Y1575097I383J923D01*
G01X359890Y1591333D01*
Y1591920D01*
G02X360659Y1592342I500J0D01*
G03X361819Y1591924I1507J2363D01*
G03X364640Y1593391I346J2781D01*
G03X364967Y1594699I-2475J1314D01*
G03X362932Y1597400I-2802J6D01*
G03X362437Y1597494I-768J-2695D01*
G02X361534Y1598489I97J995D01*
G01Y1600921D01*
G02X362437Y1601916I1000J0D01*
G03X362394Y1607498I-271J2789D01*
G02X361476Y1608494I82J996D01*
G01Y1612294D01*
X360204Y1613566D01*
X359219Y1614550D01*
X340241D01*
X339268Y1613578D01*
X338263Y1612573D01*
G02X337852Y1612429I-354J353D01*
G01X337795Y1612436D01*
X337770Y1612442D01*
G03X335511Y1607443I-606J-2736D01*
G03X335829Y1607242I1653J2263D01*
G02X336047Y1605662I-489J-872D01*
G01X330142Y1599757D01*
Y1595706D01*
X311787Y1577351D01*
X311663Y1577315D01*
G03Y1574427I414J-1444D01*
G01X311787Y1574391D01*
X326032Y1560146D01*
Y1420554D01*
X322014Y1416536D01*
X164077D01*
X152851Y1405310D01*
X98039D01*
X86694Y1393965D01*
G02X85012Y1394665I-682J732D01*
G01Y1461992D01*
X111302Y1488282D01*
G02X112612Y1488373I707J-707D01*
G03X114716Y1490477I906J1198D01*
G02X114807Y1491787I798J603D01*
G01X114973Y1491953D01*
X115174Y1492155D01*
Y1719799D01*
G02X115320Y1720152I500J0D01*
G01X118763Y1723594D01*
X123209Y1728040D01*
X167153D01*
X173685Y1734572D01*
X173809Y1734607D01*
G03X174838Y1735636I-415J1444D01*
G01X174873Y1735760D01*
X182977Y1743864D01*
X342582D01*
X367150Y1768433D01*
Y1771354D01*
X364877Y1773628D01*
X362988Y1775517D01*
G02X363271Y1777130I707J707D01*
G03X364208Y1781623I-1106J2575D01*
G03X364054Y1781775I-2044J-1917D01*
G03X361971Y1782500I-1888J-2070D01*
G03X359790Y1781191I194J-2795D01*
G02X359366Y1780956I-424J265D01*
G01X357768D01*
G02X357268Y1781456I0J500D01*
G02X357677Y1781948I500J0D01*
G03X359382Y1786419I-511J2756D01*
G03X357492Y1787488I-2217J-1714D01*
G03X356687Y1787466I-327J-2783D01*
G03X356615Y1787453I462J-2764D01*
G03X355493Y1786954I550J-2748D01*
G03X355105Y1786605I1672J-2249D01*
G03X354790Y1786191I2063J-1896D01*
G02X354365Y1785956I-424J265D01*
G01X353695D01*
X349029Y1790622D01*
X335766D01*
X333742Y1788598D01*
G02X332034Y1789234I-709J706D01*
G01Y1832030D01*
G02X332181Y1832383I500J-1D01*
G01X337802Y1838003D01*
Y1902753D01*
X344692Y1909643D01*
X344816Y1909679D01*
G03X345344Y1909953I-414J1444D01*
G03X345846Y1910708I-942J1170D01*
G01X345881Y1910832D01*
X355355Y1920306D01*
G02X356953Y1920053I707J-707D01*
G03X358945Y1922045I1365J627D01*
G02X358692Y1923643I454J891D01*
G01X362096Y1927047D01*
X366192Y1931144D01*
Y1940451D01*
X367188Y1941447D01*
Y1952013D01*
G02X368869Y1952662I998J-83D01*
G03X367041Y1959456I4516J4858D01*
G02X365378Y1959040I-956J291D01*
G01X362975Y1961443D01*
X362546Y1961871D01*
X359139Y1965278D01*
X340969D01*
X339638Y1963948D01*
X338263Y1962573D01*
G02X337852Y1962429I-354J353D01*
G01X337795Y1962436D01*
X337769Y1962442D01*
G03X336046Y1957136I-606J-2736D01*
G02X336353Y1955512I-400J-917D01*
G01X334383Y1953542D01*
X331148Y1950306D01*
Y1927627D01*
X331085Y1927514D01*
G03Y1926060I1314J-727D01*
G01X331148Y1925947D01*
Y1918213D01*
G02X331001Y1917859I-500J0D01*
G01X330773Y1917632D01*
X330676Y1917535D01*
Y1840752D01*
X326132Y1836208D01*
Y1835971D01*
X325582Y1835420D01*
Y1771379D01*
X317591Y1763388D01*
X167284D01*
X167247Y1763352D01*
X167090D01*
X151217Y1747479D01*
X111741D01*
X91292Y1727030D01*
Y1677739D01*
G02X90792Y1677239I-500J0D01*
G01X88067D01*
X49031Y1716275D01*
X48974Y1716580D01*
X49037Y1716721D01*
G03X46815Y1714499I-3981J1759D01*
G01X46956Y1714562D01*
X47261Y1714505D01*
X89830Y1671936D01*
Y1499712D01*
X47900Y1457782D01*
Y1349024D01*
G02X46218Y1348375I-998J83D01*
G01X45585Y1349008D01*
X34828D01*
X34456Y1349380D01*
G02X34601Y1350914I707J707D01*
G03X31150Y1354365I-1334J2117D01*
G02X29616Y1354220I-827J562D01*
G01X28906Y1354930D01*
X28737D01*
G02X27774Y1356199I0J1000D01*
G03X23012I-2381J769D01*
G02X22049Y1354930I-963J-269D01*
G01X18895D01*
G02X17932Y1356199I0J1000D01*
G03X17984Y1357553I-2381J769D01*
G03X16345Y1359341I-2433J-585D01*
G03X15798Y1359458I-793J-2372D01*
G03X13821Y1358776I-247J-2490D01*
G03X13064Y1356691I1730J-1808D01*
G03X13296Y1355883I2487J277D01*
G03X13523Y1355503I2253J1088D01*
G01X13567Y1355442D01*
X13621Y1355282D01*
G02X13501Y1354769I-474J-160D01*
G01X13014Y1354282D01*
X10109D01*
X9712Y1354489D01*
X9630Y1354596D01*
G03X8514Y1355389I-1952J-1565D01*
G03X6456Y1355215I-837J-2358D01*
G02X5000Y1356105I-456J890D01*
G01Y1357831D01*
G02X6456Y1358721I1000J0D01*
G03Y1363089I1221J2184D01*
G02X5000Y1363979I-456J890D01*
G01Y1365705D01*
G02X6456Y1366595I1000J0D01*
G03Y1370963I1221J2184D01*
G02X5000Y1371853I-456J890D01*
G01Y1373579D01*
G02X6456Y1374469I1000J0D01*
G03Y1378837I1221J2184D01*
G02X5000Y1379727I-456J890D01*
G01Y1381453D01*
G02X6456Y1382343I1000J0D01*
G03Y1386711I1221J2184D01*
G02X5000Y1387601I-456J890D01*
G01Y2064961D01*
G02X5125Y2065421I906J1D01*
G02X5211Y2065543I781J-459D01*
G02X5246Y2065583I699J-577D01*
G01X5255Y2065592D01*
X5260Y2065598D01*
G02X5933Y2065867I645J-637D01*
G01X5965Y2065866D01*
X92520D01*
G03X98062Y2067380I-1J10905D01*
G03X98724Y2067804I-5546J9389D01*
G01X98725D01*
X98732Y2067810D01*
G03X100230Y2069061I-6213J8962D01*
G03X100715Y2069579I-7713J7708D01*
G03X100734Y2069600I-8075J7325D01*
G03X101039Y2069965I-8213J7173D01*
G03X101271Y2070266I-8519J6806D01*
G03X101911Y2071230I-8752J6505D01*
G03X103424Y2076772I-9392J5542D01*
G01Y2080709D01*
G02X104288Y2081614I907J-1D01*
G01X397638D01*
G02X400512Y2078740I0J-2874D01*
G01Y7874D01*
G02X399896Y6097I-2874J1D01*
G02X399503Y5906I-393J309D01*
G01X103924D01*
G02X103424Y6406I0J500D01*
G01Y9843D01*
G03X97765Y19402I-10904J-1D01*
G03X95602Y20302I-5246J-9559D01*
G03X93740Y20678I-3081J-10460D01*
G03X93562Y20697I-1246J-10833D01*
G03X92866Y20741I-1036J-10855D01*
G01X92852D01*
G03X92604Y20746I-344J-10898D01*
G01X92521Y20747D01*
X92519Y20748D01*
X5875D01*
G02X5100Y21237I30J906D01*
G02X5011Y21505I806J416D01*
G02X5000Y21613I895J146D01*
G02X4999Y21667I906J44D01*
G02X5000Y21703I907J-7D01*
G01Y716098D01*
G02X6463Y716985I1000J1D01*
G03Y721365I1210J2190D01*
G02X5000Y722252I-463J886D01*
G01Y723972D01*
G02X6463Y724859I1000J1D01*
G03Y729239I1210J2190D01*
G02X5000Y730126I-463J886D01*
G01Y731846D01*
G02X6463Y732733I1000J1D01*
G03Y737113I1210J2190D01*
G02X5000Y738000I-463J886D01*
G01Y739720D01*
G02X6463Y740607I1000J1D01*
G03Y744987I1210J2190D01*
G02X5000Y745874I-463J886D01*
G01Y747594D01*
G02X6463Y748481I1000J1D01*
G03Y752861I1210J2190D01*
G02X5000Y753748I-463J886D01*
G01Y755468D01*
G02X6463Y756355I1000J1D01*
G03X6486Y756342I1242J2171D01*
G03X8577Y756212I1187J2203D01*
G03X9956Y757520I-903J2333D01*
G02X11000Y758102I912J-409D01*
G01X12682Y756420D01*
X12847D01*
G02X13347Y755920I0J-500D01*
G01Y755805D01*
X13297Y755701D01*
G03X13053Y754412I2250J-1094D01*
G03X13107Y754054I2494J193D01*
G03X13115Y754020I2439J556D01*
G03X13241Y753636I2433J586D01*
G03X17224Y752751I2306J972D01*
G02X17997Y752976I642J-767D01*
G01X22655Y748318D01*
X22797D01*
X23089Y748026D01*
Y747723D01*
X23055Y747636D01*
G03X23000Y747477I2336J-897D01*
G03X22994Y747458I2382J-763D01*
G03X27678Y745723I2395J-725D01*
G02X28696Y746252I887J-463D01*
G01X30221Y744726D01*
X30622D01*
G02X31122Y744226I0J-500D01*
G01Y744099D01*
X31062Y743988D01*
G03X30770Y742581I2201J-1191D01*
G03X33227Y740295I2493J216D01*
G03X35750Y742519I36J2502D01*
G01Y742520D01*
X35751Y742532D01*
G02X36601Y742818I496J-67D01*
G01X36824Y742595D01*
Y700368D01*
X54832Y682360D01*
G02X54097Y681262I-991J-131D01*
G03X55935Y679424I386J-1452D01*
G02X57033Y680159I967J-256D01*
G01X74514Y662678D01*
Y520612D01*
X32384Y478482D01*
Y450855D01*
X45766Y437472D01*
Y423321D01*
X40946Y418501D01*
Y357854D01*
X53244Y345556D01*
Y300282D01*
X41118Y288156D01*
Y239887D01*
X69279Y211727D01*
G02X69425Y211374I-354J-353D01*
G01Y165863D01*
X34602Y131040D01*
Y105390D01*
G02X33167Y105233I-793J610D01*
G03Y98781I-2694J-3226D01*
G02X34602Y98624I642J-768D01*
G01Y83736D01*
X35432Y82906D01*
G02Y82198I-353J-354D01*
G01X35302Y82068D01*
X34935Y82039D01*
X34786Y82147D01*
G03X24696Y81775I-4807J-6647D01*
G03X22057Y77627I5283J-6275D01*
G03X38181Y75388I7922J-2127D01*
G02X39181Y76374I1000J-14D01*
G01X40328D01*
X42734Y73968D01*
Y54321D01*
X53199Y43857D01*
G02X52860Y42967I-991J-132D01*
G03X52567Y42681I2120J-2465D01*
G03X52130Y42068I2412J-2182D01*
G03X55786Y37350I2849J-1568D01*
G03X58153Y39794I-807J3150D01*
G01X58191Y39965D01*
X58465Y40185D01*
X58642D01*
G02X59142Y39685I0J-500D01*
G01Y39568D01*
X60583Y38126D01*
X61457Y37252D01*
X61743Y36963D01*
G02X61884Y36551I-356J-352D01*
G01X61873Y36465D01*
X61861Y36426D01*
G03X66567Y32662I3118J-926D01*
G03X64759Y38745I-1587J2838D01*
G03X64256Y38671I220J-3245D01*
G03X64247Y38669I701J-3176D01*
G03X64109Y38634I730J-3169D01*
G01X64106Y38633D01*
X64077Y38625D01*
X64017Y38607D01*
X63940Y38595D01*
G02X63513Y38736I-73J495D01*
G01X61791Y40458D01*
G02X61644Y40781I352J355D01*
G01Y42016D01*
G02X63176Y42793I998J-70D01*
G03X66900Y42876I1803J2707D01*
G03X67478Y43419I-1921J2624D01*
G03X67695Y43711I-2498J2083D01*
G03X68086Y46460I-2716J1789D01*
G01X68045Y46593D01*
X68112Y46863D01*
X71080Y49831D01*
Y58989D01*
X68371Y61698D01*
X68177D01*
G02X67421Y63352I0J1000D01*
G03X68227Y65670I-2442J2148D01*
G03X66690Y68266I-3248J-170D01*
G03X63999Y68601I-1711J-2766D01*
G03X62100Y67013I980J-3101D01*
G03X62091Y66998I2781J-1679D01*
G02X61660Y66752I-431J254D01*
G01X58223D01*
G02X57439Y68373I0J1000D01*
G03X57426Y72642I-2460J2127D01*
G03X54217Y73662I-2447J-2142D01*
G02X53746Y73795I-117J486D01*
G01X52150Y75391D01*
Y79506D01*
X44162Y87493D01*
G02X44016Y87846I354J353D01*
G01Y108622D01*
G02X45749Y108355I793J-611D01*
G03X51449Y99642I19605J6605D01*
G03X65354Y94272I13905J15318D01*
G03X71133Y95096I-1J20687D01*
G03X72408Y95512I-5776J19865D01*
G03X79006Y99417I-7055J19447D01*
G03X86041Y114960I-13652J15543D01*
G03X84112Y123683I-20687J0D01*
G03X84023Y123873I-18778J-8680D01*
G03X80796Y128727I-18669J-8912D01*
G03X75698Y132876I-15442J-13767D01*
G03X65354Y135648I-10345J-17916D01*
G01X64866D01*
Y135642D01*
G03X61177Y135221I492J-20681D01*
G03X45746Y121555I4177J-20261D01*
G02X44016Y121298I-937J353D01*
G01Y126929D01*
G02X44162Y127282I500J0D01*
G01X79052Y162171D01*
Y215273D01*
X50534Y243791D01*
Y284226D01*
X62678Y296371D01*
Y349467D01*
X50380Y361765D01*
Y414590D01*
X50940Y415150D01*
G02X51648I354J-353D01*
G01X51756Y415041D01*
X51785Y414890D01*
G03X55680Y412324I3194J610D01*
G03X56217Y412493I-704J3175D01*
G03X55588Y418694I-1238J3007D01*
G02X55182Y419185I94J491D01*
G01Y441376D01*
X41944Y454613D01*
G02X41798Y454966I354J353D01*
G01Y474579D01*
X83928Y516709D01*
Y662989D01*
G02X85405Y663113I795J-607D01*
G01X88576Y659942D01*
Y420034D01*
X84764Y416222D01*
Y358452D01*
X89586Y353629D01*
X93596Y349619D01*
Y101120D01*
X106672Y88044D01*
G02X106464Y86471I-707J-707D01*
G03X108464Y84338I749J-1302D01*
G01X108519Y84421D01*
X108871Y84658D01*
X108969Y84678D01*
G03X109521Y84911I-296J1472D01*
G02X110088Y84628I-140J-990D01*
G01X113252Y81464D01*
Y72970D01*
X114935Y71286D01*
X116327Y69894D01*
G02X116466Y69452I-353J-354D01*
G01X116449Y69360D01*
X116435Y69321D01*
G03X118670Y71556I3485J-1250D01*
G01X118631Y71542D01*
X118539Y71525D01*
G02X118097Y71664I-88J492D01*
G01X115901Y73860D01*
G02X115754Y74192I352J355D01*
G01Y74678D01*
G02X117407Y75352I998J-83D01*
G03X123253Y79683I2513J2718D01*
G02X123549Y80906I903J429D01*
G01X126701D01*
X128614Y78993D01*
Y67303D01*
X136236Y59682D01*
G02X136382Y59329I-354J-353D01*
G01Y59163D01*
X136362Y59095D01*
G03X141856Y54915I3558J-1025D01*
G03X138815Y61604I-1936J3156D01*
G02X138312Y61728I-149J477D01*
G01X131530Y68511D01*
Y80201D01*
X127909Y83822D01*
X122502D01*
G02X122431Y85350I607J794D01*
G03X118542Y91507I-2510J2721D01*
G03X118257Y84763I1378J-3436D01*
G03X118402Y84694I1663J3308D01*
G01X118403D01*
G02X118697Y84238I-206J-456D01*
G01Y84030D01*
X118405Y83738D01*
X118063D01*
X117815Y83822D01*
X117376D01*
X97768Y103429D01*
G02X97622Y103782I354J353D01*
G01Y349607D01*
G02X98548Y349991I795J-607D01*
G01X110510Y338028D01*
X206071D01*
X291810Y252289D01*
Y235354D01*
X316135Y211028D01*
X322129D01*
X326016Y207141D01*
Y195243D01*
X329800Y191460D01*
G02X329946Y191107I-354J-353D01*
G01Y51778D01*
X329935Y51726D01*
G03X330089Y50682I1468J-317D01*
G01X330152Y50569D01*
Y22255D01*
X338481Y13926D01*
X358155D01*
X359587Y15357D01*
X361067Y16837D01*
G02X361478Y16981I354J-353D01*
G01X361535Y16974D01*
X361560Y16968D01*
G03X359408Y20216I604J2737D01*
G02X358916Y19807I-492J91D01*
G02X358416Y20307I0J500D01*
G01Y21906D01*
G02X358651Y22330I500J0D01*
G03X359353Y22955I-1486J2375D01*
G03X359374Y22981I-2169J1773D01*
G03X359800Y23751I-2208J1725D01*
G03X359940Y24316I-2635J953D01*
G03X359794Y25675I-2775J389D01*
G03X357676Y27462I-2630J-968D01*
G02X357267Y27954I91J492D01*
G02X357767Y28454I500J0D01*
G01X359366D01*
G02X359790Y28219I0J-500D01*
G03Y31191I2375J1486D01*
G02X359366Y30956I-424J265D01*
G01X358097D01*
G02X357742Y31103I-1J500D01*
G01X357708Y31138D01*
X357534Y31312D01*
Y31727D01*
X357778Y31971D01*
G03X359774Y33683I-613J2734D01*
G03X359460Y36313I-2609J1022D01*
G03X359415Y36375I-2290J-1615D01*
G03X356766Y37479I-2250J-1670D01*
G01X356760Y37478D01*
X356743Y37476D01*
X356709Y37473D01*
G02X356314Y37618I-41J498D01*
G01X349892Y44039D01*
G02X349746Y44392I354J353D01*
G01Y50494D01*
X349757Y50546D01*
G03X349603Y51590I-1468J317D01*
G01X349540Y51703D01*
Y57470D01*
X339368Y67642D01*
Y191437D01*
G02X340819Y192247I998J-83D01*
G03X343353Y192167I1346J2458D01*
G03X343524Y192254I-1184J2540D01*
G03X344213Y192792I-1359J2451D01*
G03X344254Y192837I-2051J1910D01*
G03X344480Y193126I-2090J1867D01*
G03X344962Y194530I-2314J1579D01*
G01X344974Y194719D01*
X345254Y194999D01*
X345669D01*
X346006Y194662D01*
X348908D01*
G02X349401Y194245I0J-500D01*
G01Y194244D01*
G03X349966Y192968I2764J461D01*
G03X350135Y192774I2195J1741D01*
G03X350250Y192660I2029J1932D01*
G03X350294Y192619I1932J2029D01*
G03X354416Y193036I1871J2086D01*
G03X354967Y194731I-2251J1669D01*
G03X350921Y197216I-2802J-26D01*
G01X350816Y197164D01*
X350609D01*
G02X349727Y198570I32J1000D01*
G03X349902Y200310I-2562J1136D01*
G01X349901Y200313D01*
X349895Y200341D01*
G02X350029Y200800I489J106D01*
G01X350070Y200841D01*
Y201147D01*
G02X351339Y202027I998J-84D01*
G03X354964Y204843I826J2678D01*
G01X354963Y204856D01*
Y204863D01*
G03X354548Y206179I-2797J-159D01*
G03X354504Y206248I-2384J-1472D01*
G03X353651Y207080I-2338J-1544D01*
G02X353416Y207504I265J424D01*
G01Y209109D01*
G02X353916Y209609I500J0D01*
G01X354097D01*
X354374Y209379D01*
X354407Y209200D01*
G03X354490Y208870I2755J517D01*
G03X355370Y207553I2675J835D01*
G03X355495Y207455I1791J2155D01*
G03X359967Y209751I1670J2250D01*
G03X359963Y209857I-2802J-53D01*
G03X359962Y209868I-2790J-248D01*
G03X357867Y212418I-2797J-163D01*
G03X357842Y212424I-666J-2721D01*
G03X356163Y212322I-677J-2719D01*
G03X356108Y212300I1013J-2612D01*
G03X355139Y211641I1057J-2595D01*
G02X353416Y212300I-723J691D01*
G01Y215065D01*
X350774Y217708D01*
X350442Y218040D01*
Y226942D01*
X331409Y245975D01*
X331374Y246099D01*
G03X330345Y247128I-1444J-415D01*
G01X330221Y247163D01*
X220931Y356453D01*
G02X221031Y357954I707J707D01*
G01X302140D01*
X307408Y352686D01*
X346612D01*
X356876Y342423D01*
G02X357022Y342070I-354J-353D01*
G01Y335136D01*
X360778Y331379D01*
Y325349D01*
X360767Y325297D01*
G03X363705I1469J-314D01*
G01X363694Y325349D01*
Y331617D01*
X363705Y331669D01*
G03Y332298I-1469J315D01*
G01X363694Y332350D01*
G37*
%LPC*%
G75*
G36*
G01X170004Y727205D02*
G02X156767Y727182I-6619J0D01*
G02X169983Y727726I6618J30D01*
G02X169986Y727689I-6594J-553D01*
G02X170004Y727205I-6600J-488D01*
G37*
G36*
G01Y552205D02*
G02X156767Y552182I-6619J0D01*
G02X169983Y552726I6618J30D01*
G02X169986Y552689I-6594J-553D01*
G02X170004Y552205I-6600J-488D01*
G37*
G36*
G01X169982Y1952727D02*
G02X170003Y1952205I-6597J-527D01*
G02X156766I-6618J0D01*
G02X169982Y1952727I6618J0D01*
G37*
G36*
G01X177767Y1917015D02*
G03X176567I-600J-800D01*
G02Y1919419I-900J1202D01*
G03X177767I600J800D01*
G02Y1917015I900J-1202D01*
G37*
G36*
G01X170271D02*
G03X169071I-600J-800D01*
G02Y1919419I-900J1202D01*
G03X170271I600J800D01*
G02Y1917015I900J-1202D01*
G37*
G36*
G01X161448D02*
G03X160248I-600J-800D01*
G02Y1919419I-900J1202D01*
G03X161448I600J800D01*
G02Y1917015I900J-1202D01*
G37*
G36*
G01X154020D02*
G03X152820I-600J-800D01*
G02Y1919419I-900J1202D01*
G03X154020I600J800D01*
G02Y1917015I900J-1202D01*
G37*
G36*
G01X177767Y1909496D02*
G03X176567I-600J-800D01*
G02Y1911900I-900J1202D01*
G03X177767I600J800D01*
G02Y1909496I900J-1202D01*
G37*
G36*
G01X170271D02*
G03X169071I-600J-800D01*
G02Y1911900I-900J1202D01*
G03X170271I600J800D01*
G02Y1909496I900J-1202D01*
G37*
G36*
G01X161448D02*
G03X160248I-600J-800D01*
G02Y1911900I-900J1202D01*
G03X161448I600J800D01*
G02Y1909496I900J-1202D01*
G37*
G36*
G01X154020D02*
G03X152820I-600J-800D01*
G02Y1911900I-900J1202D01*
G03X154020I600J800D01*
G02Y1909496I900J-1202D01*
G37*
G36*
G01X177767Y1901460D02*
G03X176567I-600J-800D01*
G02Y1903864I-900J1202D01*
G03X177767I600J800D01*
G02Y1901460I900J-1202D01*
G37*
G36*
G01X170271D02*
G03X169071I-600J-800D01*
G02Y1903864I-900J1202D01*
G03X170271I600J800D01*
G02Y1901460I900J-1202D01*
G37*
G36*
G01X161448D02*
G03X160248I-600J-800D01*
G02Y1903864I-900J1202D01*
G03X161448I600J800D01*
G02Y1901460I900J-1202D01*
G37*
G36*
G01X154020D02*
G03X152820I-600J-800D01*
G02Y1903864I-900J1202D01*
G03X154020I600J800D01*
G02Y1901460I900J-1202D01*
G37*
G36*
G01X177767Y1894017D02*
G03X176567I-600J-800D01*
G02Y1896421I-900J1202D01*
G03X177767I600J800D01*
G02Y1894017I900J-1202D01*
G37*
G36*
G01X170271D02*
G03X169071I-600J-800D01*
G02Y1896421I-900J1202D01*
G03X170271I600J800D01*
G02Y1894017I900J-1202D01*
G37*
G36*
G01X161448D02*
G03X160248I-600J-800D01*
G02Y1896421I-900J1202D01*
G03X161448I600J800D01*
G02Y1894017I900J-1202D01*
G37*
G36*
G01X154020D02*
G03X152820I-600J-800D01*
G02Y1896421I-900J1202D01*
G03X154020I600J800D01*
G02Y1894017I900J-1202D01*
G37*
G36*
G01X177938Y1886099D02*
G03X176738I-600J-800D01*
G02Y1888503I-900J1202D01*
G03X177938I600J800D01*
G02Y1886099I900J-1202D01*
G37*
G36*
G01X170442D02*
G03X169242I-600J-800D01*
G02Y1888503I-900J1202D01*
G03X170442I600J800D01*
G02Y1886099I900J-1202D01*
G37*
G36*
G01X161619D02*
G03X160419I-600J-800D01*
G02Y1888503I-900J1202D01*
G03X161619I600J800D01*
G02Y1886099I900J-1202D01*
G37*
G36*
G01X154191D02*
G03X152991I-600J-800D01*
G02Y1888503I-900J1202D01*
G03X154191I600J800D01*
G02Y1886099I900J-1202D01*
G37*
G36*
G01X177938Y1879504D02*
G03X176738I-600J-800D01*
G02Y1881908I-900J1202D01*
G03X177938I600J800D01*
G02Y1879504I900J-1202D01*
G37*
G36*
G01X170442D02*
G03X169242I-600J-800D01*
G02Y1881908I-900J1202D01*
G03X170442I600J800D01*
G02Y1879504I900J-1202D01*
G37*
G36*
G01X161619D02*
G03X160419I-600J-800D01*
G02Y1881908I-900J1202D01*
G03X161619I600J800D01*
G02Y1879504I900J-1202D01*
G37*
G36*
G01X154191D02*
G03X152991I-600J-800D01*
G02Y1881908I-900J1202D01*
G03X154191I600J800D01*
G02Y1879504I900J-1202D01*
G37*
G36*
G01X177938Y1872020D02*
G03X176738I-600J-800D01*
G02Y1874424I-900J1202D01*
G03X177938I600J800D01*
G02Y1872020I900J-1202D01*
G37*
G36*
G01X170442D02*
G03X169242I-600J-800D01*
G02Y1874424I-900J1202D01*
G03X170442I600J800D01*
G02Y1872020I900J-1202D01*
G37*
G36*
G01X161619D02*
G03X160419I-600J-800D01*
G02Y1874424I-900J1202D01*
G03X161619I600J800D01*
G02Y1872020I900J-1202D01*
G37*
G36*
G01X154191D02*
G03X152991I-600J-800D01*
G02Y1874424I-900J1202D01*
G03X154191I600J800D01*
G02Y1872020I900J-1202D01*
G37*
G36*
G01X294833Y1881121D02*
X294834Y1885021D01*
G02X299158Y1894363I12254J0D01*
G02X315014I7928J-9324D01*
G02X319338Y1885021I-7930J-9342D01*
G01Y1881121D01*
G02X315169Y1871913I-12253J0D01*
G02X299006Y1871910I-8083J9189D01*
G02X294833Y1881121I8080J9211D01*
G37*
G36*
G01X161619Y1864801D02*
G03X160419I-600J-800D01*
G02Y1867205I-900J1202D01*
G03X161619I600J800D01*
G02Y1864801I900J-1202D01*
G37*
G36*
G01X154191D02*
G03X152991I-600J-800D01*
G02Y1867205I-900J1202D01*
G03X154191I600J800D01*
G02Y1864801I900J-1202D01*
G37*
G36*
G01X106044Y1792524D02*
G03X106113Y1793671I-782J623D01*
G02X108567Y1793525I1278J789D01*
G03X108498Y1792378I782J-623D01*
G02X106044Y1792524I-1278J-789D01*
G37*
G36*
G01X169982Y1777727D02*
G02X170003Y1777205I-6597J-527D01*
G02X156766I-6618J0D01*
G02X169982Y1777727I6618J0D01*
G37*
G36*
G01X244807Y1714179D02*
G03X243607I-600J-800D01*
G02Y1716583I-900J1202D01*
G03X244807I600J800D01*
G02Y1714179I900J-1202D01*
G37*
G36*
G01X237311D02*
G03X236111I-600J-800D01*
G02Y1716583I-900J1202D01*
G03X237311I600J800D01*
G02Y1714179I900J-1202D01*
G37*
G36*
G01X228488D02*
G03X227288I-600J-800D01*
G02Y1716583I-900J1202D01*
G03X228488I600J800D01*
G02Y1714179I900J-1202D01*
G37*
G36*
G01X221060D02*
G03X219860I-600J-800D01*
G02Y1716583I-900J1202D01*
G03X221060I600J800D01*
G02Y1714179I900J-1202D01*
G37*
G36*
G01X244807Y1706660D02*
G03X243607I-600J-800D01*
G02Y1709064I-900J1202D01*
G03X244807I600J800D01*
G02Y1706660I900J-1202D01*
G37*
G36*
G01X237311D02*
G03X236111I-600J-800D01*
G02Y1709064I-900J1202D01*
G03X237311I600J800D01*
G02Y1706660I900J-1202D01*
G37*
G36*
G01X228488D02*
G03X227288I-600J-800D01*
G02Y1709064I-900J1202D01*
G03X228488I600J800D01*
G02Y1706660I900J-1202D01*
G37*
G36*
G01X221060D02*
G03X219860I-600J-800D01*
G02Y1709064I-900J1202D01*
G03X221060I600J800D01*
G02Y1706660I900J-1202D01*
G37*
G36*
G01X244807Y1698624D02*
G03X243607I-600J-800D01*
G02Y1701028I-900J1202D01*
G03X244807I600J800D01*
G02Y1698624I900J-1202D01*
G37*
G36*
G01X237311D02*
G03X236111I-600J-800D01*
G02Y1701028I-900J1202D01*
G03X237311I600J800D01*
G02Y1698624I900J-1202D01*
G37*
G36*
G01X228488D02*
G03X227288I-600J-800D01*
G02Y1701028I-900J1202D01*
G03X228488I600J800D01*
G02Y1698624I900J-1202D01*
G37*
G36*
G01X221060D02*
G03X219860I-600J-800D01*
G02Y1701028I-900J1202D01*
G03X221060I600J800D01*
G02Y1698624I900J-1202D01*
G37*
G36*
G01X244807Y1691181D02*
G03X243607I-600J-800D01*
G02Y1693585I-900J1202D01*
G03X244807I600J800D01*
G02Y1691181I900J-1202D01*
G37*
G36*
G01X237311D02*
G03X236111I-600J-800D01*
G02Y1693585I-900J1202D01*
G03X237311I600J800D01*
G02Y1691181I900J-1202D01*
G37*
G36*
G01X228488D02*
G03X227288I-600J-800D01*
G02Y1693585I-900J1202D01*
G03X228488I600J800D01*
G02Y1691181I900J-1202D01*
G37*
G36*
G01X221060D02*
G03X219860I-600J-800D01*
G02Y1693585I-900J1202D01*
G03X221060I600J800D01*
G02Y1691181I900J-1202D01*
G37*
G36*
G01X244978Y1683263D02*
G03X243778I-600J-800D01*
G02Y1685667I-900J1202D01*
G03X244978I600J800D01*
G02Y1683263I900J-1202D01*
G37*
G36*
G01X237482D02*
G03X236282I-600J-800D01*
G02Y1685667I-900J1202D01*
G03X237482I600J800D01*
G02Y1683263I900J-1202D01*
G37*
G36*
G01X228659D02*
G03X227459I-600J-800D01*
G02Y1685667I-900J1202D01*
G03X228659I600J800D01*
G02Y1683263I900J-1202D01*
G37*
G36*
G01X221231D02*
G03X220031I-600J-800D01*
G02Y1685667I-900J1202D01*
G03X221231I600J800D01*
G02Y1683263I900J-1202D01*
G37*
G36*
G01X244978Y1676668D02*
G03X243778I-600J-800D01*
G02Y1679072I-900J1202D01*
G03X244978I600J800D01*
G02Y1676668I900J-1202D01*
G37*
G36*
G01X237482D02*
G03X236282I-600J-800D01*
G02Y1679072I-900J1202D01*
G03X237482I600J800D01*
G02Y1676668I900J-1202D01*
G37*
G36*
G01X228659D02*
G03X227459I-600J-800D01*
G02Y1679072I-900J1202D01*
G03X228659I600J800D01*
G02Y1676668I900J-1202D01*
G37*
G36*
G01X221231D02*
G03X220031I-600J-800D01*
G02Y1679072I-900J1202D01*
G03X221231I600J800D01*
G02Y1676668I900J-1202D01*
G37*
G36*
G01X244978Y1669184D02*
G03X243778I-600J-800D01*
G02Y1671588I-900J1202D01*
G03X244978I600J800D01*
G02Y1669184I900J-1202D01*
G37*
G36*
G01X237482D02*
G03X236282I-600J-800D01*
G02Y1671588I-900J1202D01*
G03X237482I600J800D01*
G02Y1669184I900J-1202D01*
G37*
G36*
G01X228659D02*
G03X227459I-600J-800D01*
G02Y1671588I-900J1202D01*
G03X228659I600J800D01*
G02Y1669184I900J-1202D01*
G37*
G36*
G01X221231D02*
G03X220031I-600J-800D01*
G02Y1671588I-900J1202D01*
G03X221231I600J800D01*
G02Y1669184I900J-1202D01*
G37*
G36*
G01X228659Y1661965D02*
G03X227459I-600J-800D01*
G02Y1664369I-900J1202D01*
G03X228659I600J800D01*
G02Y1661965I900J-1202D01*
G37*
G36*
G01X221231D02*
G03X220031I-600J-800D01*
G02Y1664369I-900J1202D01*
G03X221231I600J800D01*
G02Y1661965I900J-1202D01*
G37*
G36*
G01X169982Y1602727D02*
G02X170003Y1602205I-6597J-527D01*
G02X156766I-6618J0D01*
G02X169982Y1602727I6618J0D01*
G37*
G36*
G01X179785Y1550233D02*
G03X178585I-600J-800D01*
G02Y1552637I-900J1202D01*
G03X179785I600J800D01*
G02Y1550233I900J-1202D01*
G37*
G36*
G01X172289D02*
G03X171089I-600J-800D01*
G02Y1552637I-900J1202D01*
G03X172289I600J800D01*
G02Y1550233I900J-1202D01*
G37*
G36*
G01X163466D02*
G03X162266I-600J-800D01*
G02Y1552637I-900J1202D01*
G03X163466I600J800D01*
G02Y1550233I900J-1202D01*
G37*
G36*
G01X156038D02*
G03X154838I-600J-800D01*
G02Y1552637I-900J1202D01*
G03X156038I600J800D01*
G02Y1550233I900J-1202D01*
G37*
G36*
G01X179785Y1542714D02*
G03X178585I-600J-800D01*
G02Y1545118I-900J1202D01*
G03X179785I600J800D01*
G02Y1542714I900J-1202D01*
G37*
G36*
G01X172289D02*
G03X171089I-600J-800D01*
G02Y1545118I-900J1202D01*
G03X172289I600J800D01*
G02Y1542714I900J-1202D01*
G37*
G36*
G01X163466D02*
G03X162266I-600J-800D01*
G02Y1545118I-900J1202D01*
G03X163466I600J800D01*
G02Y1542714I900J-1202D01*
G37*
G36*
G01X156038D02*
G03X154838I-600J-800D01*
G02Y1545118I-900J1202D01*
G03X156038I600J800D01*
G02Y1542714I900J-1202D01*
G37*
G36*
G01X179785Y1534678D02*
G03X178585I-600J-800D01*
G02Y1537082I-900J1202D01*
G03X179785I600J800D01*
G02Y1534678I900J-1202D01*
G37*
G36*
G01X172289D02*
G03X171089I-600J-800D01*
G02Y1537082I-900J1202D01*
G03X172289I600J800D01*
G02Y1534678I900J-1202D01*
G37*
G36*
G01X163466D02*
G03X162266I-600J-800D01*
G02Y1537082I-900J1202D01*
G03X163466I600J800D01*
G02Y1534678I900J-1202D01*
G37*
G36*
G01X156038D02*
G03X154838I-600J-800D01*
G02Y1537082I-900J1202D01*
G03X156038I600J800D01*
G02Y1534678I900J-1202D01*
G37*
G36*
G01X179785Y1527235D02*
G03X178585I-600J-800D01*
G02Y1529639I-900J1202D01*
G03X179785I600J800D01*
G02Y1527235I900J-1202D01*
G37*
G36*
G01X172289D02*
G03X171089I-600J-800D01*
G02Y1529639I-900J1202D01*
G03X172289I600J800D01*
G02Y1527235I900J-1202D01*
G37*
G36*
G01X163466D02*
G03X162266I-600J-800D01*
G02Y1529639I-900J1202D01*
G03X163466I600J800D01*
G02Y1527235I900J-1202D01*
G37*
G36*
G01X156038D02*
G03X154838I-600J-800D01*
G02Y1529639I-900J1202D01*
G03X156038I600J800D01*
G02Y1527235I900J-1202D01*
G37*
G36*
G01X179956Y1519317D02*
G03X178756I-600J-800D01*
G02Y1521721I-900J1202D01*
G03X179956I600J800D01*
G02Y1519317I900J-1202D01*
G37*
G36*
G01X172460D02*
G03X171260I-600J-800D01*
G02Y1521721I-900J1202D01*
G03X172460I600J800D01*
G02Y1519317I900J-1202D01*
G37*
G36*
G01X163637D02*
G03X162437I-600J-800D01*
G02Y1521721I-900J1202D01*
G03X163637I600J800D01*
G02Y1519317I900J-1202D01*
G37*
G36*
G01X156209D02*
G03X155009I-600J-800D01*
G02Y1521721I-900J1202D01*
G03X156209I600J800D01*
G02Y1519317I900J-1202D01*
G37*
G36*
G01X179956Y1512722D02*
G03X178756I-600J-800D01*
G02Y1515126I-900J1202D01*
G03X179956I600J800D01*
G02Y1512722I900J-1202D01*
G37*
G36*
G01X172460D02*
G03X171260I-600J-800D01*
G02Y1515126I-900J1202D01*
G03X172460I600J800D01*
G02Y1512722I900J-1202D01*
G37*
G36*
G01X163637D02*
G03X162437I-600J-800D01*
G02Y1515126I-900J1202D01*
G03X163637I600J800D01*
G02Y1512722I900J-1202D01*
G37*
G36*
G01X156209D02*
G03X155009I-600J-800D01*
G02Y1515126I-900J1202D01*
G03X156209I600J800D01*
G02Y1512722I900J-1202D01*
G37*
G36*
G01X179956Y1505238D02*
G03X178756I-600J-800D01*
G02Y1507642I-900J1202D01*
G03X179956I600J800D01*
G02Y1505238I900J-1202D01*
G37*
G36*
G01X172460D02*
G03X171260I-600J-800D01*
G02Y1507642I-900J1202D01*
G03X172460I600J800D01*
G02Y1505238I900J-1202D01*
G37*
G36*
G01X163637D02*
G03X162437I-600J-800D01*
G02Y1507642I-900J1202D01*
G03X163637I600J800D01*
G02Y1505238I900J-1202D01*
G37*
G36*
G01X156209D02*
G03X155009I-600J-800D01*
G02Y1507642I-900J1202D01*
G03X156209I600J800D01*
G02Y1505238I900J-1202D01*
G37*
G36*
G01X163637Y1498019D02*
G03X162437I-600J-800D01*
G02Y1500423I-900J1202D01*
G03X163637I600J800D01*
G02Y1498019I900J-1202D01*
G37*
G36*
G01X156209D02*
G03X155009I-600J-800D01*
G02Y1500423I-900J1202D01*
G03X156209I600J800D01*
G02Y1498019I900J-1202D01*
G37*
G36*
G01X169982Y1427727D02*
G02X170003Y1427205I-6597J-527D01*
G02X156766I-6618J0D01*
G02X169982Y1427727I6618J0D01*
G37*
G36*
G01X365269Y1375008D02*
G03X364069I-600J-800D01*
G02Y1377412I-900J1202D01*
G03X365269I600J800D01*
G02Y1375008I900J-1202D01*
G37*
G36*
G01X353491D02*
G03X352291I-600J-800D01*
G02Y1377412I-900J1202D01*
G03X353491I600J800D01*
G02Y1375008I900J-1202D01*
G37*
G36*
G01X365269Y1366569D02*
G03X364069I-600J-800D01*
G02Y1368973I-900J1202D01*
G03X365269I600J800D01*
G02Y1366569I900J-1202D01*
G37*
G36*
G01X353491D02*
G03X352291I-600J-800D01*
G02Y1368973I-900J1202D01*
G03X353491I600J800D01*
G02Y1366569I900J-1202D01*
G37*
G36*
G01X365269Y1358841D02*
G03X364069I-600J-800D01*
G02Y1361245I-900J1202D01*
G03X365269I600J800D01*
G02Y1358841I900J-1202D01*
G37*
G36*
G01X353491D02*
G03X352291I-600J-800D01*
G02Y1361245I-900J1202D01*
G03X353491I600J800D01*
G02Y1358841I900J-1202D01*
G37*
G36*
G01X365269Y1349504D02*
G03X364069I-600J-800D01*
G02Y1351908I-900J1202D01*
G03X365269I600J800D01*
G02Y1349504I900J-1202D01*
G37*
G36*
G01X353491D02*
G03X352291I-600J-800D01*
G02Y1351908I-900J1202D01*
G03X353491I600J800D01*
G02Y1349504I900J-1202D01*
G37*
G36*
G01X365269Y1338999D02*
G03X364069I-600J-800D01*
G02Y1341403I-900J1202D01*
G03X365269I600J800D01*
G02Y1338999I900J-1202D01*
G37*
G36*
G01X353491D02*
G03X352291I-600J-800D01*
G02Y1341403I-900J1202D01*
G03X353491I600J800D01*
G02Y1338999I900J-1202D01*
G37*
G36*
G01X365269Y1328484D02*
G03X364069I-600J-800D01*
G02Y1330888I-900J1202D01*
G03X365269I600J800D01*
G02Y1328484I900J-1202D01*
G37*
G36*
G01X353491D02*
G03X352291I-600J-800D01*
G02Y1330888I-900J1202D01*
G03X353491I600J800D01*
G02Y1328484I900J-1202D01*
G37*
G36*
G01X169982Y1252727D02*
G02X170003Y1252205I-6597J-527D01*
G02X156766I-6618J0D01*
G02X169982Y1252727I6618J0D01*
G37*
G36*
G01X254078Y1214094D02*
G03X252878I-600J-800D01*
G02Y1216498I-900J1202D01*
G03X254078I600J800D01*
G02Y1214094I900J-1202D01*
G37*
G36*
G01X246582D02*
G03X245382I-600J-800D01*
G02Y1216498I-900J1202D01*
G03X246582I600J800D01*
G02Y1214094I900J-1202D01*
G37*
G36*
G01X237759D02*
G03X236559I-600J-800D01*
G02Y1216498I-900J1202D01*
G03X237759I600J800D01*
G02Y1214094I900J-1202D01*
G37*
G36*
G01X230331D02*
G03X229131I-600J-800D01*
G02Y1216498I-900J1202D01*
G03X230331I600J800D01*
G02Y1214094I900J-1202D01*
G37*
G36*
G01X254078Y1206575D02*
G03X252878I-600J-800D01*
G02Y1208979I-900J1202D01*
G03X254078I600J800D01*
G02Y1206575I900J-1202D01*
G37*
G36*
G01X246582D02*
G03X245382I-600J-800D01*
G02Y1208979I-900J1202D01*
G03X246582I600J800D01*
G02Y1206575I900J-1202D01*
G37*
G36*
G01X237759D02*
G03X236559I-600J-800D01*
G02Y1208979I-900J1202D01*
G03X237759I600J800D01*
G02Y1206575I900J-1202D01*
G37*
G36*
G01X230331D02*
G03X229131I-600J-800D01*
G02Y1208979I-900J1202D01*
G03X230331I600J800D01*
G02Y1206575I900J-1202D01*
G37*
G36*
G01X254078Y1198539D02*
G03X252878I-600J-800D01*
G02Y1200943I-900J1202D01*
G03X254078I600J800D01*
G02Y1198539I900J-1202D01*
G37*
G36*
G01X246582D02*
G03X245382I-600J-800D01*
G02Y1200943I-900J1202D01*
G03X246582I600J800D01*
G02Y1198539I900J-1202D01*
G37*
G36*
G01X237759D02*
G03X236559I-600J-800D01*
G02Y1200943I-900J1202D01*
G03X237759I600J800D01*
G02Y1198539I900J-1202D01*
G37*
G36*
G01X230331D02*
G03X229131I-600J-800D01*
G02Y1200943I-900J1202D01*
G03X230331I600J800D01*
G02Y1198539I900J-1202D01*
G37*
G36*
G01X178800Y1197051D02*
G03X177600I-600J-800D01*
G02Y1199455I-900J1202D01*
G03X178800I600J800D01*
G02Y1197051I900J-1202D01*
G37*
G36*
G01X171304D02*
G03X170104I-600J-800D01*
G02Y1199455I-900J1202D01*
G03X171304I600J800D01*
G02Y1197051I900J-1202D01*
G37*
G36*
G01X162481D02*
G03X161281I-600J-800D01*
G02Y1199455I-900J1202D01*
G03X162481I600J800D01*
G02Y1197051I900J-1202D01*
G37*
G36*
G01X155053D02*
G03X153853I-600J-800D01*
G02Y1199455I-900J1202D01*
G03X155053I600J800D01*
G02Y1197051I900J-1202D01*
G37*
G36*
G01X178971Y1189133D02*
G03X177771I-600J-800D01*
G02Y1191537I-900J1202D01*
G03X178971I600J800D01*
G02Y1189133I900J-1202D01*
G37*
G36*
G01X171475D02*
G03X170275I-600J-800D01*
G02Y1191537I-900J1202D01*
G03X171475I600J800D01*
G02Y1189133I900J-1202D01*
G37*
G36*
G01X162652D02*
G03X161452I-600J-800D01*
G02Y1191537I-900J1202D01*
G03X162652I600J800D01*
G02Y1189133I900J-1202D01*
G37*
G36*
G01X155224D02*
G03X154024I-600J-800D01*
G02Y1191537I-900J1202D01*
G03X155224I600J800D01*
G02Y1189133I900J-1202D01*
G37*
G36*
G01X178971Y1182538D02*
G03X177771I-600J-800D01*
G02Y1184942I-900J1202D01*
G03X178971I600J800D01*
G02Y1182538I900J-1202D01*
G37*
G36*
G01X171475D02*
G03X170275I-600J-800D01*
G02Y1184942I-900J1202D01*
G03X171475I600J800D01*
G02Y1182538I900J-1202D01*
G37*
G36*
G01X162652D02*
G03X161452I-600J-800D01*
G02Y1184942I-900J1202D01*
G03X162652I600J800D01*
G02Y1182538I900J-1202D01*
G37*
G36*
G01X155224D02*
G03X154024I-600J-800D01*
G02Y1184942I-900J1202D01*
G03X155224I600J800D01*
G02Y1182538I900J-1202D01*
G37*
G36*
G01X178971Y1175054D02*
G03X177771I-600J-800D01*
G02Y1177458I-900J1202D01*
G03X178971I600J800D01*
G02Y1175054I900J-1202D01*
G37*
G36*
G01X171475D02*
G03X170275I-600J-800D01*
G02Y1177458I-900J1202D01*
G03X171475I600J800D01*
G02Y1175054I900J-1202D01*
G37*
G36*
G01X162652D02*
G03X161452I-600J-800D01*
G02Y1177458I-900J1202D01*
G03X162652I600J800D01*
G02Y1175054I900J-1202D01*
G37*
G36*
G01X155224D02*
G03X154024I-600J-800D01*
G02Y1177458I-900J1202D01*
G03X155224I600J800D01*
G02Y1175054I900J-1202D01*
G37*
G36*
G01X162652Y1167835D02*
G03X161452I-600J-800D01*
G02Y1170239I-900J1202D01*
G03X162652I600J800D01*
G02Y1167835I900J-1202D01*
G37*
G36*
G01X155224D02*
G03X154024I-600J-800D01*
G02Y1170239I-900J1202D01*
G03X155224I600J800D01*
G02Y1167835I900J-1202D01*
G37*
G36*
G01X169982Y1077727D02*
G02X170003Y1077205I-6597J-527D01*
G02X156766I-6618J0D01*
G02X169982Y1077727I6618J0D01*
G37*
G36*
G01X257015Y1003466D02*
G03X255815I-600J-800D01*
G02Y1005870I-900J1202D01*
G03X257015I600J800D01*
G02Y1003466I900J-1202D01*
G37*
G36*
G01X249519D02*
G03X248319I-600J-800D01*
G02Y1005870I-900J1202D01*
G03X249519I600J800D01*
G02Y1003466I900J-1202D01*
G37*
G36*
G01X240696D02*
G03X239496I-600J-800D01*
G02Y1005870I-900J1202D01*
G03X240696I600J800D01*
G02Y1003466I900J-1202D01*
G37*
G36*
G01X233268D02*
G03X232068I-600J-800D01*
G02Y1005870I-900J1202D01*
G03X233268I600J800D01*
G02Y1003466I900J-1202D01*
G37*
G36*
G01X257015Y995947D02*
G03X255815I-600J-800D01*
G02Y998351I-900J1202D01*
G03X257015I600J800D01*
G02Y995947I900J-1202D01*
G37*
G36*
G01X249519D02*
G03X248319I-600J-800D01*
G02Y998351I-900J1202D01*
G03X249519I600J800D01*
G02Y995947I900J-1202D01*
G37*
G36*
G01X240696D02*
G03X239496I-600J-800D01*
G02Y998351I-900J1202D01*
G03X240696I600J800D01*
G02Y995947I900J-1202D01*
G37*
G36*
G01X233268D02*
G03X232068I-600J-800D01*
G02Y998351I-900J1202D01*
G03X233268I600J800D01*
G02Y995947I900J-1202D01*
G37*
G36*
G01X257015Y987911D02*
G03X255815I-600J-800D01*
G02Y990315I-900J1202D01*
G03X257015I600J800D01*
G02Y987911I900J-1202D01*
G37*
G36*
G01X249519D02*
G03X248319I-600J-800D01*
G02Y990315I-900J1202D01*
G03X249519I600J800D01*
G02Y987911I900J-1202D01*
G37*
G36*
G01X240696D02*
G03X239496I-600J-800D01*
G02Y990315I-900J1202D01*
G03X240696I600J800D01*
G02Y987911I900J-1202D01*
G37*
G36*
G01X233268D02*
G03X232068I-600J-800D01*
G02Y990315I-900J1202D01*
G03X233268I600J800D01*
G02Y987911I900J-1202D01*
G37*
G36*
G01X257015Y980468D02*
G03X255815I-600J-800D01*
G02Y982872I-900J1202D01*
G03X257015I600J800D01*
G02Y980468I900J-1202D01*
G37*
G36*
G01X249519D02*
G03X248319I-600J-800D01*
G02Y982872I-900J1202D01*
G03X249519I600J800D01*
G02Y980468I900J-1202D01*
G37*
G36*
G01X240696D02*
G03X239496I-600J-800D01*
G02Y982872I-900J1202D01*
G03X240696I600J800D01*
G02Y980468I900J-1202D01*
G37*
G36*
G01X233268D02*
G03X232068I-600J-800D01*
G02Y982872I-900J1202D01*
G03X233268I600J800D01*
G02Y980468I900J-1202D01*
G37*
G36*
G01X257186Y972550D02*
G03X255986I-600J-800D01*
G02Y974954I-900J1202D01*
G03X257186I600J800D01*
G02Y972550I900J-1202D01*
G37*
G36*
G01X249690D02*
G03X248490I-600J-800D01*
G02Y974954I-900J1202D01*
G03X249690I600J800D01*
G02Y972550I900J-1202D01*
G37*
G36*
G01X240867D02*
G03X239667I-600J-800D01*
G02Y974954I-900J1202D01*
G03X240867I600J800D01*
G02Y972550I900J-1202D01*
G37*
G36*
G01X233439D02*
G03X232239I-600J-800D01*
G02Y974954I-900J1202D01*
G03X233439I600J800D01*
G02Y972550I900J-1202D01*
G37*
G36*
G01X104281Y971032D02*
G03X103586Y971077I-371J-335D01*
G02X103725Y973228I-975J1143D01*
G03X104420Y973183I371J335D01*
G02X104281Y971032I975J-1143D01*
G37*
G36*
G01X257186Y965955D02*
G03X255986I-600J-800D01*
G02Y968359I-900J1202D01*
G03X257186I600J800D01*
G02Y965955I900J-1202D01*
G37*
G36*
G01X249690D02*
G03X248490I-600J-800D01*
G02Y968359I-900J1202D01*
G03X249690I600J800D01*
G02Y965955I900J-1202D01*
G37*
G36*
G01X240867D02*
G03X239667I-600J-800D01*
G02Y968359I-900J1202D01*
G03X240867I600J800D01*
G02Y965955I900J-1202D01*
G37*
G36*
G01X233439D02*
G03X232239I-600J-800D01*
G02Y968359I-900J1202D01*
G03X233439I600J800D01*
G02Y965955I900J-1202D01*
G37*
G36*
G01X257186Y958471D02*
G03X255986I-600J-800D01*
G02Y960875I-900J1202D01*
G03X257186I600J800D01*
G02Y958471I900J-1202D01*
G37*
G36*
G01X249690D02*
G03X248490I-600J-800D01*
G02Y960875I-900J1202D01*
G03X249690I600J800D01*
G02Y958471I900J-1202D01*
G37*
G36*
G01X240867D02*
G03X239667I-600J-800D01*
G02Y960875I-900J1202D01*
G03X240867I600J800D01*
G02Y958471I900J-1202D01*
G37*
G36*
G01X233439D02*
G03X232239I-600J-800D01*
G02Y960875I-900J1202D01*
G03X233439I600J800D01*
G02Y958471I900J-1202D01*
G37*
G36*
G01X240867Y951252D02*
G03X239667I-600J-800D01*
G02Y953656I-900J1202D01*
G03X240867I600J800D01*
G02Y951252I900J-1202D01*
G37*
G36*
G01X233439D02*
G03X232239I-600J-800D01*
G02Y953656I-900J1202D01*
G03X233439I600J800D01*
G02Y951252I900J-1202D01*
G37*
G36*
G01X169982Y902727D02*
G02X170003Y902205I-6597J-527D01*
G02X156766I-6618J0D01*
G02X169982Y902727I6618J0D01*
G37*
G36*
G01X181120Y866518D02*
G03X179920I-600J-800D01*
G02Y868922I-900J1202D01*
G03X181120I600J800D01*
G02Y866518I900J-1202D01*
G37*
G36*
G01X173624D02*
G03X172424I-600J-800D01*
G02Y868922I-900J1202D01*
G03X173624I600J800D01*
G02Y866518I900J-1202D01*
G37*
G36*
G01X164801D02*
G03X163601I-600J-800D01*
G02Y868922I-900J1202D01*
G03X164801I600J800D01*
G02Y866518I900J-1202D01*
G37*
G36*
G01X157373D02*
G03X156173I-600J-800D01*
G02Y868922I-900J1202D01*
G03X157373I600J800D01*
G02Y866518I900J-1202D01*
G37*
G36*
G01X181120Y858999D02*
G03X179920I-600J-800D01*
G02Y861403I-900J1202D01*
G03X181120I600J800D01*
G02Y858999I900J-1202D01*
G37*
G36*
G01X173624D02*
G03X172424I-600J-800D01*
G02Y861403I-900J1202D01*
G03X173624I600J800D01*
G02Y858999I900J-1202D01*
G37*
G36*
G01X164801D02*
G03X163601I-600J-800D01*
G02Y861403I-900J1202D01*
G03X164801I600J800D01*
G02Y858999I900J-1202D01*
G37*
G36*
G01X157373D02*
G03X156173I-600J-800D01*
G02Y861403I-900J1202D01*
G03X157373I600J800D01*
G02Y858999I900J-1202D01*
G37*
G36*
G01X181120Y850963D02*
G03X179920I-600J-800D01*
G02Y853367I-900J1202D01*
G03X181120I600J800D01*
G02Y850963I900J-1202D01*
G37*
G36*
G01X173624D02*
G03X172424I-600J-800D01*
G02Y853367I-900J1202D01*
G03X173624I600J800D01*
G02Y850963I900J-1202D01*
G37*
G36*
G01X164801D02*
G03X163601I-600J-800D01*
G02Y853367I-900J1202D01*
G03X164801I600J800D01*
G02Y850963I900J-1202D01*
G37*
G36*
G01X157373D02*
G03X156173I-600J-800D01*
G02Y853367I-900J1202D01*
G03X157373I600J800D01*
G02Y850963I900J-1202D01*
G37*
G36*
G01X181120Y843520D02*
G03X179920I-600J-800D01*
G02Y845924I-900J1202D01*
G03X181120I600J800D01*
G02Y843520I900J-1202D01*
G37*
G36*
G01X173624D02*
G03X172424I-600J-800D01*
G02Y845924I-900J1202D01*
G03X173624I600J800D01*
G02Y843520I900J-1202D01*
G37*
G36*
G01X164801D02*
G03X163601I-600J-800D01*
G02Y845924I-900J1202D01*
G03X164801I600J800D01*
G02Y843520I900J-1202D01*
G37*
G36*
G01X157373D02*
G03X156173I-600J-800D01*
G02Y845924I-900J1202D01*
G03X157373I600J800D01*
G02Y843520I900J-1202D01*
G37*
G36*
G01X181291Y835602D02*
G03X180091I-600J-800D01*
G02Y838006I-900J1202D01*
G03X181291I600J800D01*
G02Y835602I900J-1202D01*
G37*
G36*
G01X173795D02*
G03X172595I-600J-800D01*
G02Y838006I-900J1202D01*
G03X173795I600J800D01*
G02Y835602I900J-1202D01*
G37*
G36*
G01X164972D02*
G03X163772I-600J-800D01*
G02Y838006I-900J1202D01*
G03X164972I600J800D01*
G02Y835602I900J-1202D01*
G37*
G36*
G01X157544D02*
G03X156344I-600J-800D01*
G02Y838006I-900J1202D01*
G03X157544I600J800D01*
G02Y835602I900J-1202D01*
G37*
G36*
G01X181291Y829007D02*
G03X180091I-600J-800D01*
G02Y831411I-900J1202D01*
G03X181291I600J800D01*
G02Y829007I900J-1202D01*
G37*
G36*
G01X173795D02*
G03X172595I-600J-800D01*
G02Y831411I-900J1202D01*
G03X173795I600J800D01*
G02Y829007I900J-1202D01*
G37*
G36*
G01X164972D02*
G03X163772I-600J-800D01*
G02Y831411I-900J1202D01*
G03X164972I600J800D01*
G02Y829007I900J-1202D01*
G37*
G36*
G01X157544D02*
G03X156344I-600J-800D01*
G02Y831411I-900J1202D01*
G03X157544I600J800D01*
G02Y829007I900J-1202D01*
G37*
G36*
G01X181291Y821523D02*
G03X180091I-600J-800D01*
G02Y823927I-900J1202D01*
G03X181291I600J800D01*
G02Y821523I900J-1202D01*
G37*
G36*
G01X173795D02*
G03X172595I-600J-800D01*
G02Y823927I-900J1202D01*
G03X173795I600J800D01*
G02Y821523I900J-1202D01*
G37*
G36*
G01X164972D02*
G03X163772I-600J-800D01*
G02Y823927I-900J1202D01*
G03X164972I600J800D01*
G02Y821523I900J-1202D01*
G37*
G36*
G01X157544D02*
G03X156344I-600J-800D01*
G02Y823927I-900J1202D01*
G03X157544I600J800D01*
G02Y821523I900J-1202D01*
G37*
G36*
G01X253639Y637822D02*
G03X252439I-600J-800D01*
G02Y640226I-900J1202D01*
G03X253639I600J800D01*
G02Y637822I900J-1202D01*
G37*
G36*
G01X246143D02*
G03X244943I-600J-800D01*
G02Y640226I-900J1202D01*
G03X246143I600J800D01*
G02Y637822I900J-1202D01*
G37*
G36*
G01X237320D02*
G03X236120I-600J-800D01*
G02Y640226I-900J1202D01*
G03X237320I600J800D01*
G02Y637822I900J-1202D01*
G37*
G36*
G01X229892D02*
G03X228692I-600J-800D01*
G02Y640226I-900J1202D01*
G03X229892I600J800D01*
G02Y637822I900J-1202D01*
G37*
G36*
G01X253639Y630303D02*
G03X252439I-600J-800D01*
G02Y632707I-900J1202D01*
G03X253639I600J800D01*
G02Y630303I900J-1202D01*
G37*
G36*
G01X246143D02*
G03X244943I-600J-800D01*
G02Y632707I-900J1202D01*
G03X246143I600J800D01*
G02Y630303I900J-1202D01*
G37*
G36*
G01X237320D02*
G03X236120I-600J-800D01*
G02Y632707I-900J1202D01*
G03X237320I600J800D01*
G02Y630303I900J-1202D01*
G37*
G36*
G01X229892D02*
G03X228692I-600J-800D01*
G02Y632707I-900J1202D01*
G03X229892I600J800D01*
G02Y630303I900J-1202D01*
G37*
G36*
G01X278144Y623425D02*
G03X276944I-600J-800D01*
G02Y625829I-900J1202D01*
G03X278144I600J800D01*
G02Y623425I900J-1202D01*
G37*
G36*
G01X266533Y623119D02*
G03X265333I-600J-800D01*
G02Y625523I-900J1202D01*
G03X266533I600J800D01*
G02Y623119I900J-1202D01*
G37*
G36*
G01X253639Y622267D02*
G03X252439I-600J-800D01*
G02Y624671I-900J1202D01*
G03X253639I600J800D01*
G02Y622267I900J-1202D01*
G37*
G36*
G01X246143D02*
G03X244943I-600J-800D01*
G02Y624671I-900J1202D01*
G03X246143I600J800D01*
G02Y622267I900J-1202D01*
G37*
G36*
G01X237320D02*
G03X236120I-600J-800D01*
G02Y624671I-900J1202D01*
G03X237320I600J800D01*
G02Y622267I900J-1202D01*
G37*
G36*
G01X229892D02*
G03X228692I-600J-800D01*
G02Y624671I-900J1202D01*
G03X229892I600J800D01*
G02Y622267I900J-1202D01*
G37*
G36*
G01X253639Y614824D02*
G03X252439I-600J-800D01*
G02Y617228I-900J1202D01*
G03X253639I600J800D01*
G02Y614824I900J-1202D01*
G37*
G36*
G01X246143D02*
G03X244943I-600J-800D01*
G02Y617228I-900J1202D01*
G03X246143I600J800D01*
G02Y614824I900J-1202D01*
G37*
G36*
G01X237320D02*
G03X236120I-600J-800D01*
G02Y617228I-900J1202D01*
G03X237320I600J800D01*
G02Y614824I900J-1202D01*
G37*
G36*
G01X229892D02*
G03X228692I-600J-800D01*
G02Y617228I-900J1202D01*
G03X229892I600J800D01*
G02Y614824I900J-1202D01*
G37*
G36*
G01X253810Y606906D02*
G03X252610I-600J-800D01*
G02Y609310I-900J1202D01*
G03X253810I600J800D01*
G02Y606906I900J-1202D01*
G37*
G36*
G01X246314D02*
G03X245114I-600J-800D01*
G02Y609310I-900J1202D01*
G03X246314I600J800D01*
G02Y606906I900J-1202D01*
G37*
G36*
G01X237491D02*
G03X236291I-600J-800D01*
G02Y609310I-900J1202D01*
G03X237491I600J800D01*
G02Y606906I900J-1202D01*
G37*
G36*
G01X230063D02*
G03X228863I-600J-800D01*
G02Y609310I-900J1202D01*
G03X230063I600J800D01*
G02Y606906I900J-1202D01*
G37*
G36*
G01X253810Y600311D02*
G03X252610I-600J-800D01*
G02Y602715I-900J1202D01*
G03X253810I600J800D01*
G02Y600311I900J-1202D01*
G37*
G36*
G01X246314D02*
G03X245114I-600J-800D01*
G02Y602715I-900J1202D01*
G03X246314I600J800D01*
G02Y600311I900J-1202D01*
G37*
G36*
G01X237491D02*
G03X236291I-600J-800D01*
G02Y602715I-900J1202D01*
G03X237491I600J800D01*
G02Y600311I900J-1202D01*
G37*
G36*
G01X230063D02*
G03X228863I-600J-800D01*
G02Y602715I-900J1202D01*
G03X230063I600J800D01*
G02Y600311I900J-1202D01*
G37*
G36*
G01X253810Y592827D02*
G03X252610I-600J-800D01*
G02Y595231I-900J1202D01*
G03X253810I600J800D01*
G02Y592827I900J-1202D01*
G37*
G36*
G01X246314D02*
G03X245114I-600J-800D01*
G02Y595231I-900J1202D01*
G03X246314I600J800D01*
G02Y592827I900J-1202D01*
G37*
G36*
G01X237491D02*
G03X236291I-600J-800D01*
G02Y595231I-900J1202D01*
G03X237491I600J800D01*
G02Y592827I900J-1202D01*
G37*
G36*
G01X230063D02*
G03X228863I-600J-800D01*
G02Y595231I-900J1202D01*
G03X230063I600J800D01*
G02Y592827I900J-1202D01*
G37*
G36*
G01X158359Y512726D02*
G03X157159I-600J-800D01*
G02Y515130I-900J1202D01*
G03X158359I600J800D01*
G02Y512726I900J-1202D01*
G37*
G36*
G01X247796Y512095D02*
G03X246596I-600J-800D01*
G02Y514499I-900J1202D01*
G03X247796I600J800D01*
G02Y512095I900J-1202D01*
G37*
G36*
G01X240300D02*
G03X239100I-600J-800D01*
G02Y514499I-900J1202D01*
G03X240300I600J800D01*
G02Y512095I900J-1202D01*
G37*
G36*
G01X231477D02*
G03X230277I-600J-800D01*
G02Y514499I-900J1202D01*
G03X231477I600J800D01*
G02Y512095I900J-1202D01*
G37*
G36*
G01X158359Y505207D02*
G03X157159I-600J-800D01*
G02Y507611I-900J1202D01*
G03X158359I600J800D01*
G02Y505207I900J-1202D01*
G37*
G36*
G01X247796Y504576D02*
G03X246596I-600J-800D01*
G02Y506980I-900J1202D01*
G03X247796I600J800D01*
G02Y504576I900J-1202D01*
G37*
G36*
G01X240300D02*
G03X239100I-600J-800D01*
G02Y506980I-900J1202D01*
G03X240300I600J800D01*
G02Y504576I900J-1202D01*
G37*
G36*
G01X231477D02*
G03X230277I-600J-800D01*
G02Y506980I-900J1202D01*
G03X231477I600J800D01*
G02Y504576I900J-1202D01*
G37*
G36*
G01X158359Y497171D02*
G03X157159I-600J-800D01*
G02Y499575I-900J1202D01*
G03X158359I600J800D01*
G02Y497171I900J-1202D01*
G37*
G36*
G01X247796Y496540D02*
G03X246596I-600J-800D01*
G02Y498944I-900J1202D01*
G03X247796I600J800D01*
G02Y496540I900J-1202D01*
G37*
G36*
G01X240300D02*
G03X239100I-600J-800D01*
G02Y498944I-900J1202D01*
G03X240300I600J800D01*
G02Y496540I900J-1202D01*
G37*
G36*
G01X231477D02*
G03X230277I-600J-800D01*
G02Y498944I-900J1202D01*
G03X231477I600J800D01*
G02Y496540I900J-1202D01*
G37*
G36*
G01X158359Y489728D02*
G03X157159I-600J-800D01*
G02Y492132I-900J1202D01*
G03X158359I600J800D01*
G02Y489728I900J-1202D01*
G37*
G36*
G01X247796Y489097D02*
G03X246596I-600J-800D01*
G02Y491501I-900J1202D01*
G03X247796I600J800D01*
G02Y489097I900J-1202D01*
G37*
G36*
G01X240300D02*
G03X239100I-600J-800D01*
G02Y491501I-900J1202D01*
G03X240300I600J800D01*
G02Y489097I900J-1202D01*
G37*
G36*
G01X231477D02*
G03X230277I-600J-800D01*
G02Y491501I-900J1202D01*
G03X231477I600J800D01*
G02Y489097I900J-1202D01*
G37*
G36*
G01X158530Y481810D02*
G03X157330I-600J-800D01*
G02Y484214I-900J1202D01*
G03X158530I600J800D01*
G02Y481810I900J-1202D01*
G37*
G36*
G01X247967Y481179D02*
G03X246767I-600J-800D01*
G02Y483583I-900J1202D01*
G03X247967I600J800D01*
G02Y481179I900J-1202D01*
G37*
G36*
G01X240471D02*
G03X239271I-600J-800D01*
G02Y483583I-900J1202D01*
G03X240471I600J800D01*
G02Y481179I900J-1202D01*
G37*
G36*
G01X231648D02*
G03X230448I-600J-800D01*
G02Y483583I-900J1202D01*
G03X231648I600J800D01*
G02Y481179I900J-1202D01*
G37*
G36*
G01X158530Y475215D02*
G03X157330I-600J-800D01*
G02Y477619I-900J1202D01*
G03X158530I600J800D01*
G02Y475215I900J-1202D01*
G37*
G36*
G01X247967Y474584D02*
G03X246767I-600J-800D01*
G02Y476988I-900J1202D01*
G03X247967I600J800D01*
G02Y474584I900J-1202D01*
G37*
G36*
G01X240471D02*
G03X239271I-600J-800D01*
G02Y476988I-900J1202D01*
G03X240471I600J800D01*
G02Y474584I900J-1202D01*
G37*
G36*
G01X231648D02*
G03X230448I-600J-800D01*
G02Y476988I-900J1202D01*
G03X231648I600J800D01*
G02Y474584I900J-1202D01*
G37*
G36*
G01X158530Y467731D02*
G03X157330I-600J-800D01*
G02Y470135I-900J1202D01*
G03X158530I600J800D01*
G02Y467731I900J-1202D01*
G37*
G36*
G01X247967Y467100D02*
G03X246767I-600J-800D01*
G02Y469504I-900J1202D01*
G03X247967I600J800D01*
G02Y467100I900J-1202D01*
G37*
G36*
G01X240471D02*
G03X239271I-600J-800D01*
G02Y469504I-900J1202D01*
G03X240471I600J800D01*
G02Y467100I900J-1202D01*
G37*
G36*
G01X231648D02*
G03X230448I-600J-800D01*
G02Y469504I-900J1202D01*
G03X231648I600J800D01*
G02Y467100I900J-1202D01*
G37*
G36*
G01X158530Y460512D02*
G03X157330I-600J-800D01*
G02Y462916I-900J1202D01*
G03X158530I600J800D01*
G02Y460512I900J-1202D01*
G37*
G36*
G01X231648Y459881D02*
G03X230448I-600J-800D01*
G02Y462285I-900J1202D01*
G03X231648I600J800D01*
G02Y459881I900J-1202D01*
G37*
G36*
G01X169982Y377727D02*
G02X170002Y377205I-6597J-514D01*
G02X156766I-6618J0D01*
G02X169982Y377727I6618J0D01*
G37*
G36*
G01X176962Y312606D02*
G03X175762I-600J-800D01*
G02Y315010I-900J1202D01*
G03X176962I600J800D01*
G02Y312606I900J-1202D01*
G37*
G36*
G01Y305087D02*
G03X175762I-600J-800D01*
G02Y307491I-900J1202D01*
G03X176962I600J800D01*
G02Y305087I900J-1202D01*
G37*
G36*
G01Y297051D02*
G03X175762I-600J-800D01*
G02Y299455I-900J1202D01*
G03X176962I600J800D01*
G02Y297051I900J-1202D01*
G37*
G36*
G01Y289608D02*
G03X175762I-600J-800D01*
G02Y292012I-900J1202D01*
G03X176962I600J800D01*
G02Y289608I900J-1202D01*
G37*
G36*
G01X242962Y288788D02*
G03X241762I-600J-800D01*
G02Y291192I-900J1202D01*
G03X242962I600J800D01*
G02Y288788I900J-1202D01*
G37*
G36*
G01X235466D02*
G03X234266I-600J-800D01*
G02Y291192I-900J1202D01*
G03X235466I600J800D01*
G02Y288788I900J-1202D01*
G37*
G36*
G01X226643D02*
G03X225443I-600J-800D01*
G02Y291192I-900J1202D01*
G03X226643I600J800D01*
G02Y288788I900J-1202D01*
G37*
G36*
G01X177133Y281690D02*
G03X175933I-600J-800D01*
G02Y284094I-900J1202D01*
G03X177133I600J800D01*
G02Y281690I900J-1202D01*
G37*
G36*
G01X242962Y281269D02*
G03X241762I-600J-800D01*
G02Y283673I-900J1202D01*
G03X242962I600J800D01*
G02Y281269I900J-1202D01*
G37*
G36*
G01X235466D02*
G03X234266I-600J-800D01*
G02Y283673I-900J1202D01*
G03X235466I600J800D01*
G02Y281269I900J-1202D01*
G37*
G36*
G01X226643D02*
G03X225443I-600J-800D01*
G02Y283673I-900J1202D01*
G03X226643I600J800D01*
G02Y281269I900J-1202D01*
G37*
G36*
G01X177133Y275095D02*
G03X175933I-600J-800D01*
G02Y277499I-900J1202D01*
G03X177133I600J800D01*
G02Y275095I900J-1202D01*
G37*
G36*
G01X242962Y273233D02*
G03X241762I-600J-800D01*
G02Y275637I-900J1202D01*
G03X242962I600J800D01*
G02Y273233I900J-1202D01*
G37*
G36*
G01X235466D02*
G03X234266I-600J-800D01*
G02Y275637I-900J1202D01*
G03X235466I600J800D01*
G02Y273233I900J-1202D01*
G37*
G36*
G01X226643D02*
G03X225443I-600J-800D01*
G02Y275637I-900J1202D01*
G03X226643I600J800D01*
G02Y273233I900J-1202D01*
G37*
G36*
G01X177133Y267611D02*
G03X175933I-600J-800D01*
G02Y270015I-900J1202D01*
G03X177133I600J800D01*
G02Y267611I900J-1202D01*
G37*
G36*
G01X242962Y265790D02*
G03X241762I-600J-800D01*
G02Y268194I-900J1202D01*
G03X242962I600J800D01*
G02Y265790I900J-1202D01*
G37*
G36*
G01X235466D02*
G03X234266I-600J-800D01*
G02Y268194I-900J1202D01*
G03X235466I600J800D01*
G02Y265790I900J-1202D01*
G37*
G36*
G01X226643D02*
G03X225443I-600J-800D01*
G02Y268194I-900J1202D01*
G03X226643I600J800D01*
G02Y265790I900J-1202D01*
G37*
G36*
G01X177133Y260392D02*
G03X175933I-600J-800D01*
G02Y262796I-900J1202D01*
G03X177133I600J800D01*
G02Y260392I900J-1202D01*
G37*
G36*
G01X243133Y257872D02*
G03X241933I-600J-800D01*
G02Y260276I-900J1202D01*
G03X243133I600J800D01*
G02Y257872I900J-1202D01*
G37*
G36*
G01X235637D02*
G03X234437I-600J-800D01*
G02Y260276I-900J1202D01*
G03X235637I600J800D01*
G02Y257872I900J-1202D01*
G37*
G36*
G01X226814D02*
G03X225614I-600J-800D01*
G02Y260276I-900J1202D01*
G03X226814I600J800D01*
G02Y257872I900J-1202D01*
G37*
G36*
G01X243133Y251277D02*
G03X241933I-600J-800D01*
G02Y253681I-900J1202D01*
G03X243133I600J800D01*
G02Y251277I900J-1202D01*
G37*
G36*
G01X235637D02*
G03X234437I-600J-800D01*
G02Y253681I-900J1202D01*
G03X235637I600J800D01*
G02Y251277I900J-1202D01*
G37*
G36*
G01X226814D02*
G03X225614I-600J-800D01*
G02Y253681I-900J1202D01*
G03X226814I600J800D01*
G02Y251277I900J-1202D01*
G37*
G36*
G01X243133Y243793D02*
G03X241933I-600J-800D01*
G02Y246197I-900J1202D01*
G03X243133I600J800D01*
G02Y243793I900J-1202D01*
G37*
G36*
G01X235637D02*
G03X234437I-600J-800D01*
G02Y246197I-900J1202D01*
G03X235637I600J800D01*
G02Y243793I900J-1202D01*
G37*
G36*
G01X226814D02*
G03X225614I-600J-800D01*
G02Y246197I-900J1202D01*
G03X226814I600J800D01*
G02Y243793I900J-1202D01*
G37*
G36*
G01Y236574D02*
G03X225614I-600J-800D01*
G02Y238978I-900J1202D01*
G03X226814I600J800D01*
G02Y236574I900J-1202D01*
G37*
G36*
G01X169982Y202727D02*
G02X170002Y202205I-6597J-514D01*
G02X156766I-6618J0D01*
G02X169982Y202727I6618J0D01*
G37*
G36*
G01X175857Y162419D02*
G03X174657I-600J-800D01*
G02Y164823I-900J1202D01*
G03X175857I600J800D01*
G02Y162419I900J-1202D01*
G37*
G36*
G01X168429D02*
G03X167229I-600J-800D01*
G02Y164823I-900J1202D01*
G03X168429I600J800D01*
G02Y162419I900J-1202D01*
G37*
G36*
G01X175857Y154900D02*
G03X174657I-600J-800D01*
G02Y157304I-900J1202D01*
G03X175857I600J800D01*
G02Y154900I900J-1202D01*
G37*
G36*
G01X168429D02*
G03X167229I-600J-800D01*
G02Y157304I-900J1202D01*
G03X168429I600J800D01*
G02Y154900I900J-1202D01*
G37*
G36*
G01X175857Y146864D02*
G03X174657I-600J-800D01*
G02Y149268I-900J1202D01*
G03X175857I600J800D01*
G02Y146864I900J-1202D01*
G37*
G36*
G01X168429D02*
G03X167229I-600J-800D01*
G02Y149268I-900J1202D01*
G03X168429I600J800D01*
G02Y146864I900J-1202D01*
G37*
G36*
G01X175857Y139421D02*
G03X174657I-600J-800D01*
G02Y141825I-900J1202D01*
G03X175857I600J800D01*
G02Y139421I900J-1202D01*
G37*
G36*
G01X168429D02*
G03X167229I-600J-800D01*
G02Y141825I-900J1202D01*
G03X168429I600J800D01*
G02Y139421I900J-1202D01*
G37*
G36*
G01X176028Y131503D02*
G03X174828I-600J-800D01*
G02Y133907I-900J1202D01*
G03X176028I600J800D01*
G02Y131503I900J-1202D01*
G37*
G36*
G01X168600D02*
G03X167400I-600J-800D01*
G02Y133907I-900J1202D01*
G03X168600I600J800D01*
G02Y131503I900J-1202D01*
G37*
G36*
G01X176028Y124908D02*
G03X174828I-600J-800D01*
G02Y127312I-900J1202D01*
G03X176028I600J800D01*
G02Y124908I900J-1202D01*
G37*
G36*
G01X168600D02*
G03X167400I-600J-800D01*
G02Y127312I-900J1202D01*
G03X168600I600J800D01*
G02Y124908I900J-1202D01*
G37*
G36*
G01X176028Y117424D02*
G03X174828I-600J-800D01*
G02Y119828I-900J1202D01*
G03X176028I600J800D01*
G02Y117424I900J-1202D01*
G37*
G36*
G01X168600D02*
G03X167400I-600J-800D01*
G02Y119828I-900J1202D01*
G03X168600I600J800D01*
G02Y117424I900J-1202D01*
G37*
G36*
G01X176028Y110205D02*
G03X174828I-600J-800D01*
G02Y112609I-900J1202D01*
G03X176028I600J800D01*
G02Y110205I900J-1202D01*
G37*
G36*
G01X168600D02*
G03X167400I-600J-800D01*
G02Y112609I-900J1202D01*
G03X168600I600J800D01*
G02Y110205I900J-1202D01*
G37*
G36*
G01X247380Y100792D02*
G03X246180I-600J-800D01*
G02Y103196I-900J1202D01*
G03X247380I600J800D01*
G02Y100792I900J-1202D01*
G37*
G36*
G01X239884D02*
G03X238684I-600J-800D01*
G02Y103196I-900J1202D01*
G03X239884I600J800D01*
G02Y100792I900J-1202D01*
G37*
G36*
G01X247380Y93273D02*
G03X246180I-600J-800D01*
G02Y95677I-900J1202D01*
G03X247380I600J800D01*
G02Y93273I900J-1202D01*
G37*
G36*
G01X239884D02*
G03X238684I-600J-800D01*
G02Y95677I-900J1202D01*
G03X239884I600J800D01*
G02Y93273I900J-1202D01*
G37*
G36*
G01X247380Y85237D02*
G03X246180I-600J-800D01*
G02Y87641I-900J1202D01*
G03X247380I600J800D01*
G02Y85237I900J-1202D01*
G37*
G36*
G01X239884D02*
G03X238684I-600J-800D01*
G02Y87641I-900J1202D01*
G03X239884I600J800D01*
G02Y85237I900J-1202D01*
G37*
G36*
G01X247380Y77794D02*
G03X246180I-600J-800D01*
G02Y80198I-900J1202D01*
G03X247380I600J800D01*
G02Y77794I900J-1202D01*
G37*
G36*
G01X239884D02*
G03X238684I-600J-800D01*
G02Y80198I-900J1202D01*
G03X239884I600J800D01*
G02Y77794I900J-1202D01*
G37*
G36*
G01X247551Y69876D02*
G03X246351I-600J-800D01*
G02Y72280I-900J1202D01*
G03X247551I600J800D01*
G02Y69876I900J-1202D01*
G37*
G36*
G01X240055D02*
G03X238855I-600J-800D01*
G02Y72280I-900J1202D01*
G03X240055I600J800D01*
G02Y69876I900J-1202D01*
G37*
G36*
G01X247551Y63281D02*
G03X246351I-600J-800D01*
G02Y65685I-900J1202D01*
G03X247551I600J800D01*
G02Y63281I900J-1202D01*
G37*
G36*
G01X240055D02*
G03X238855I-600J-800D01*
G02Y65685I-900J1202D01*
G03X240055I600J800D01*
G02Y63281I900J-1202D01*
G37*
G36*
G01X247551Y55797D02*
G03X246351I-600J-800D01*
G02Y58201I-900J1202D01*
G03X247551I600J800D01*
G02Y55797I900J-1202D01*
G37*
G36*
G01X240055D02*
G03X238855I-600J-800D01*
G02Y58201I-900J1202D01*
G03X240055I600J800D01*
G02Y55797I900J-1202D01*
G37*
G36*
G01X169982Y27727D02*
G02X170002Y27205I-6597J-514D01*
G02X156766I-6618J0D01*
G02X169982Y27727I6618J0D01*
G37*
G36*
G01X107500Y23528D02*
G02X105544Y23857I-1165J-948D01*
G03X105793Y25337I-527J850D01*
G02X107749Y25008I1165J948D01*
G03X107500Y23528I527J-850D01*
G37*
G36*
G01X77362Y1013681D02*
G02Y1016061I-916J1190D01*
G03X78583I611J792D01*
G02Y1013681I916J-1190D01*
G03X77362I-611J-792D01*
G37*
G36*
G01X123301Y1113673D02*
G02X116539I-3381J-1508D01*
G03X115626Y1115080I-913J407D01*
G01X114413D01*
X113848Y1114515D01*
G02X111158Y1117205I-1345J1345D01*
G01X112837Y1118884D01*
X115809D01*
G03X116683Y1120369I0J1000D01*
G02X123157I3237J1796D01*
G03X124031Y1118884I874J-485D01*
G01X125247D01*
X135230Y1128866D01*
X135818D01*
G03X136690Y1130355I0J1000D01*
G02X143150I3230J1810D01*
G03X144022Y1128866I872J-489D01*
G01X149162D01*
X150954Y1127074D01*
X155722D01*
G03X156664Y1128409I0J1000D01*
G02X157111Y1130390I1792J637D01*
G01X159695Y1132973D01*
G03X159145Y1134668I-707J707D01*
G02X160620Y1135300I237J1483D01*
G01X160518Y1135151D01*
X160550Y1134792D01*
X160678Y1134664D01*
G03X161386I354J353D01*
G01X162260Y1135538D01*
X200129D01*
X235473Y1170882D01*
X307880D01*
G03X308233Y1171029I-1J500D01*
G01X311353Y1174149D01*
G02X314043Y1171459I1345J-1345D01*
G01X310387Y1167804D01*
G03Y1167096I353J-354D01*
G01X313872Y1163611D01*
G02X311182Y1160921I-1345J-1345D01*
G01X309042Y1163061D01*
G03X308689Y1163208I-354J-353D01*
G01X238860D01*
G03X238507Y1163062I0J-500D01*
G01X203006Y1127560D01*
X164018D01*
X159729Y1123272D01*
X149378D01*
X147586Y1125064D01*
X144222D01*
G03X143307Y1123660I0J-1000D01*
G02X136219Y1122085I-3387J-1495D01*
G03X134512Y1122770I-1000J-22D01*
G01X126823Y1115080D01*
X124214D01*
G03X123301Y1113673I0J-1000D01*
G37*
G36*
G01X65355Y1494272D02*
G02X44668Y1514960I0J20687D01*
G02X86042I20687J0D01*
G02X65355Y1494272I-20687J-1D01*
G37*
G36*
G01X81440Y1769626D02*
G02X79312I-1064J-1060D01*
G03Y1771038I-708J706D01*
G02X79306Y1773152I1064J1060D01*
G03Y1774555I-713J701D01*
G02X81446I1070J1054D01*
G03Y1773152I713J-701D01*
G02X81440Y1771038I-1070J-1054D01*
G03Y1769626I708J-706D01*
G37*
G36*
G01X65355Y1844272D02*
G02X44668Y1864960I0J20687D01*
G02X86042I20687J0D01*
G02X65355Y1844272I-20687J-1D01*
G37*
G36*
G01X349379Y904405D02*
X349347Y904705D01*
X349379Y905005D01*
G02Y904405I2786J-300D01*
G37*
G36*
G01X65355Y444272D02*
G02X44667Y464960I0J20688D01*
G02X86042I20687J0D01*
G02X65355Y444272I-20687J-1D01*
G37*
G54D29*
X13441Y495961D03*
X10914Y578848D03*
X15984Y578849D03*
X11541Y1562330D03*
X11153Y1638435D03*
X16552Y1638005D03*
X61888Y666012D03*
X57124Y675327D03*
X59236Y670758D03*
X55544Y1770835D03*
X55080Y1762982D03*
X54948Y1755171D03*
X56425Y1778371D03*
X70376Y1796383D03*
X97417Y32853D03*
Y37438D03*
X91294Y926951D03*
X98139Y990959D03*
X96904Y1067515D03*
X96948Y1092036D03*
X96949Y1087095D03*
X96774Y1072226D03*
X96684Y1081791D03*
X97403Y1424340D03*
X97825Y1419492D03*
X96993Y1443743D03*
X96996Y1438980D03*
X97465Y1447919D03*
X95236Y1453321D03*
X88837Y1771103D03*
X91460Y1765062D03*
X93771Y1748227D03*
X75376Y1796236D03*
X80376Y1796163D03*
X85376Y1796236D03*
X108082Y38899D03*
X102646Y49461D03*
X101430Y41803D03*
X107405Y49898D03*
X107037Y34687D03*
X104350Y62293D03*
X107263Y72244D03*
X109054Y58250D03*
X104116Y82557D03*
X115139Y849240D03*
X100687Y999391D03*
X107351Y1093484D03*
X107235Y1081791D03*
X107215Y1072208D03*
X98652Y1096403D03*
X108779Y1105760D03*
X105152Y1118381D03*
X105684Y1125919D03*
X108468Y1129286D03*
X106962Y1434041D03*
X106921Y1419492D03*
X106763Y1444599D03*
X107006Y1452651D03*
X105455Y1472894D03*
X108574Y1463389D03*
X99103Y1765722D03*
X99068Y1760827D03*
X107355Y1770437D03*
X99047Y1785571D03*
X98873Y1780542D03*
X99294Y1789947D03*
X107373Y1780544D03*
X105669Y1815227D03*
X108819Y1812118D03*
X106819Y1802230D03*
X108819Y1824470D03*
X162384Y56744D03*
X157558Y51426D03*
X161742Y72497D03*
X162586Y68130D03*
X159417Y91281D03*
X158901Y85017D03*
X161377Y407575D03*
X156865Y401207D03*
X161257Y420869D03*
X159019Y439268D03*
X158807Y432969D03*
X156610Y751063D03*
X161826Y756757D03*
X161131Y774878D03*
X161644Y764231D03*
X158956Y780982D03*
X159053Y787280D03*
X164539Y1116135D03*
X162140Y1106853D03*
X156854Y1101031D03*
X159192Y1451105D03*
X163099Y1457084D03*
X162524Y1462651D03*
X162242Y1471380D03*
X159216Y1477124D03*
X159526Y1483434D03*
X163250Y1815631D03*
X162140Y1807740D03*
X156452Y1800821D03*
X159822Y1831380D03*
X159075Y1825087D03*
X184284Y948331D03*
X175989Y944537D03*
X176011Y936829D03*
X184196Y967371D03*
X175359Y963486D03*
X175561Y955964D03*
X175135Y972490D03*
X184632Y983423D03*
X175022Y980281D03*
X175742Y989958D03*
X175449Y997660D03*
X184353Y1001556D03*
X175698Y1008730D03*
X175473Y1016296D03*
X267627Y115559D03*
X256947Y128276D03*
X257125Y115559D03*
X267420Y147540D03*
X263086Y147675D03*
X265722Y463102D03*
X265737Y473680D03*
X264516Y497341D03*
X255837Y823626D03*
X255687Y812192D03*
X264181Y847354D03*
X267194Y1191777D03*
X262559D03*
X276523Y147585D03*
X271943Y147630D03*
X271547Y260353D03*
X276617Y256400D03*
X281193Y256624D03*
X285513Y322688D03*
X281074D03*
X289895D03*
X281569Y436169D03*
X286665Y432844D03*
X291002D03*
X274991Y463099D03*
X277776Y497341D03*
X273405D03*
X268938D03*
X285348Y610540D03*
X290984Y607215D03*
X274514Y672192D03*
X283340D03*
X278955D03*
X273114Y785968D03*
X278184Y782643D03*
X282737D03*
X270070Y812192D03*
X268686Y847488D03*
X277788Y847237D03*
X273305D03*
X285966Y959767D03*
X291194Y956442D03*
X285666Y1016162D03*
X290107D03*
X282958Y1134471D03*
X288188Y1131146D03*
X276807Y1191777D03*
X272082D03*
X283808Y1308959D03*
X289210Y1305634D03*
X284240Y1374544D03*
X279518Y1374543D03*
X275052Y1374715D03*
X270579Y1374626D03*
X275521Y1479435D03*
X279990D03*
X270234Y1482760D03*
X291054Y1543211D03*
X284086Y1659883D03*
X289421Y1656558D03*
X279703Y1723398D03*
X284583Y1723465D03*
X289499Y1723735D03*
X274704Y1723196D03*
X281066Y1834569D03*
X291550Y1829846D03*
X286623Y1829400D03*
X280240Y1858668D03*
X279976Y1864565D03*
X287121Y1898327D03*
X282717D03*
X278262D03*
X273817D03*
X299687Y78778D03*
X304151D03*
X308651D03*
X313089D03*
X294483Y82732D03*
X294506Y322688D03*
X295509Y607215D03*
X295874Y956442D03*
X294617Y1016162D03*
X292698Y1131146D03*
X313894Y1513883D03*
X302267Y1524401D03*
X301734Y1513883D03*
X304870Y1543211D03*
X300392D03*
X295675D03*
X294090Y1656558D03*
X293606Y1858668D03*
X314562Y2009087D03*
X322005Y78778D03*
X317567D03*
X337387Y586230D03*
X331867Y589810D03*
X333750Y595326D03*
X336160Y937262D03*
X337509Y1109598D03*
X328989Y1121090D03*
X326558Y1126368D03*
X325796Y1162266D03*
X324803Y2005272D03*
X320045Y2005215D03*
X359931Y52189D03*
X361799Y311938D03*
X363825Y401768D03*
X342900Y580126D03*
X354000Y652170D03*
X356559Y675167D03*
X362577Y752783D03*
X343656Y933725D03*
X344099Y1106798D03*
X348710Y1570187D03*
X361011Y1568890D03*
X348245Y1575241D03*
X355364Y1570990D03*
X352337Y1887285D03*
X363361Y1918313D03*
X363411Y1923459D03*
X372204Y56126D03*
X379257Y52158D03*
X387524Y76847D03*
X374442Y406857D03*
X374542Y401282D03*
X368907Y404308D03*
X376654Y754748D03*
X382892Y767710D03*
X386790Y774338D03*
X379335Y1189778D03*
X383276Y1184136D03*
X386816Y1179841D03*
X376472Y1194999D03*
X373674Y1199967D03*
X371523Y1204725D03*
X373564Y1352548D03*
X367829Y1566108D03*
X366306Y1899864D03*
X374431Y1901397D03*
X374775Y1919243D03*
X379403Y1917261D03*
X369748Y1921795D03*
G54D30*
X15547Y707364D03*
Y723112D03*
Y730986D03*
X25389Y723112D03*
Y730986D03*
X15547Y738860D03*
Y746734D03*
X25389Y738860D03*
X15551Y1089251D03*
Y1097125D03*
Y1104999D03*
Y1112873D03*
X25393Y1104999D03*
X15551Y1364842D03*
Y1372716D03*
Y1380590D03*
X25393Y1364842D03*
Y1372716D03*
Y1380590D03*
X15551Y1388464D03*
X25393D03*
X33263Y727049D03*
Y734923D03*
X33267Y1108936D03*
Y1360905D03*
Y1368779D03*
Y1376653D03*
Y1384527D03*
G54D28*
X14073Y512197D03*
Y522000D03*
Y552000D03*
Y561803D03*
Y1580004D03*
Y1570201D03*
Y1610004D03*
Y1619807D03*
X65254Y519500D03*
Y529500D03*
Y539500D03*
X55254Y524500D03*
Y534500D03*
X65254Y549500D03*
X55254Y544500D03*
Y554500D03*
X65254Y1577504D03*
Y1587504D03*
Y1597504D03*
X55254Y1582504D03*
Y1592504D03*
Y1602504D03*
X65254Y1607504D03*
X55254Y1612504D03*
G54D27*
X22756Y113818D03*
Y125629D03*
X22480Y316838D03*
Y340460D03*
X22756Y1866819D03*
Y1878630D03*
Y1948818D03*
Y1960629D03*
Y2023818D03*
Y2035629D03*
G54D36*
X173385Y32520D03*
Y21890D03*
X183385Y32520D03*
Y21890D03*
X193385Y32520D03*
Y21890D03*
X173385Y196890D03*
X183385D03*
X193385D03*
X173385Y207520D03*
X183385D03*
X193385D03*
X173385Y371890D03*
X183385D03*
X193385D03*
X173385Y382520D03*
X183385D03*
X193385D03*
X173386Y557520D03*
Y546890D03*
X183386Y557520D03*
Y546890D03*
X193386Y557520D03*
Y546890D03*
X173386Y732520D03*
Y721890D03*
X183386Y732520D03*
Y721890D03*
X193386Y732520D03*
Y721890D03*
X173385Y896890D03*
X183385D03*
X193385D03*
X173385Y907520D03*
X183385D03*
X193385D03*
X173385Y1071890D03*
X183385D03*
X193385D03*
X173385Y1082520D03*
X183385D03*
X193385D03*
X173385Y1257520D03*
Y1246890D03*
X183385Y1257520D03*
Y1246890D03*
X193385Y1257520D03*
Y1246890D03*
X173385Y1432520D03*
Y1421890D03*
X183385Y1432520D03*
Y1421890D03*
X193385Y1432520D03*
Y1421890D03*
X173385Y1596890D03*
X183385D03*
X193385D03*
X173385Y1607520D03*
X183385D03*
X193385D03*
X173385Y1771890D03*
X183385D03*
X193385D03*
X173385Y1782520D03*
X183385D03*
X193385D03*
X173385Y1957520D03*
Y1946890D03*
X183385Y1957520D03*
Y1946890D03*
X193385Y1957520D03*
Y1946890D03*
X203385Y32520D03*
Y21890D03*
X213385Y32520D03*
Y21890D03*
X203385Y196890D03*
X213385D03*
X203385Y207520D03*
X213385D03*
X203385Y371890D03*
X213385D03*
X203385Y382520D03*
X213385D03*
X203386Y557520D03*
Y546890D03*
X213386Y557520D03*
Y546890D03*
X203386Y732520D03*
Y721890D03*
X213386Y732520D03*
Y721890D03*
X203385Y896890D03*
X213385D03*
X203385Y907520D03*
X213385D03*
X203385Y1071890D03*
X213385D03*
X203385Y1082520D03*
X213385D03*
X203385Y1257520D03*
Y1246890D03*
X213385Y1257520D03*
Y1246890D03*
X203385Y1432520D03*
Y1421890D03*
X213385Y1432520D03*
Y1421890D03*
X203385Y1596890D03*
X213385D03*
X203385Y1607520D03*
X213385D03*
X203385Y1771890D03*
X213385D03*
X203385Y1782520D03*
X213385D03*
X203385Y1957520D03*
Y1946890D03*
X213385Y1957520D03*
Y1946890D03*
X223385Y32520D03*
Y21890D03*
X233385Y32520D03*
Y21890D03*
X243385Y32520D03*
Y21890D03*
X223385Y196890D03*
X233385D03*
X243385D03*
X223385Y207520D03*
X233385D03*
X243385D03*
X223385Y371890D03*
X233385D03*
X243385D03*
X223385Y382520D03*
X233385D03*
X243385D03*
X223386Y557520D03*
Y546890D03*
X233386Y557520D03*
Y546890D03*
X243386Y557520D03*
Y546890D03*
X223386Y732520D03*
Y721890D03*
X233386Y732520D03*
Y721890D03*
X243386Y732520D03*
Y721890D03*
X223385Y896890D03*
X233385D03*
X243385D03*
X223385Y907520D03*
X233385D03*
X243385D03*
X223385Y1071890D03*
X233385D03*
X243385D03*
X223385Y1082520D03*
X233385D03*
X243385D03*
X223385Y1257520D03*
Y1246890D03*
X233385Y1257520D03*
Y1246890D03*
X243385Y1257520D03*
Y1246890D03*
X223385Y1432520D03*
Y1421890D03*
X233385Y1432520D03*
Y1421890D03*
X243385Y1432520D03*
Y1421890D03*
X223385Y1596890D03*
X233385D03*
X243385D03*
X223385Y1607520D03*
X233385D03*
X243385D03*
X223385Y1771890D03*
X233385D03*
X243385D03*
X223385Y1782520D03*
X233385D03*
X243385D03*
X223385Y1957520D03*
Y1946890D03*
X233385Y1957520D03*
Y1946890D03*
X243385Y1957520D03*
Y1946890D03*
X337165Y1249705D03*
X357165Y199705D03*
X362165Y194705D03*
Y204705D03*
X357166Y559705D03*
X362166Y544705D03*
Y554705D03*
X342165Y894705D03*
X352165D03*
X357165Y899705D03*
X362165Y894705D03*
X357165Y909705D03*
X362165Y904705D03*
X357165Y1249705D03*
X362165Y1244705D03*
Y1254705D03*
G54D35*
X119920Y18071D03*
Y28071D03*
Y38071D03*
Y48071D03*
Y58071D03*
Y98071D03*
Y108071D03*
Y118071D03*
Y128071D03*
Y138071D03*
Y148071D03*
Y158071D03*
Y168071D03*
Y178071D03*
Y188071D03*
Y198071D03*
Y208071D03*
Y724134D03*
Y734134D03*
Y744134D03*
Y754134D03*
Y764134D03*
Y774134D03*
Y784134D03*
Y794134D03*
Y804134D03*
Y814134D03*
Y824134D03*
Y834134D03*
Y844134D03*
Y854134D03*
Y864134D03*
Y874134D03*
Y884134D03*
Y894134D03*
Y904134D03*
Y1062165D03*
Y1072165D03*
Y1082165D03*
Y1092165D03*
Y1102165D03*
Y1132165D03*
Y1142165D03*
Y1152165D03*
Y1162165D03*
Y1172165D03*
Y1182165D03*
Y1192165D03*
Y1202165D03*
Y1212165D03*
Y1222165D03*
Y1232165D03*
Y1242165D03*
Y1252165D03*
Y1410197D03*
Y1420197D03*
Y1430197D03*
Y1440197D03*
Y1450197D03*
Y1460197D03*
Y1470197D03*
Y1480197D03*
Y1490197D03*
Y1500197D03*
Y1510197D03*
Y1520197D03*
Y1530197D03*
Y1540197D03*
Y1550197D03*
Y1560197D03*
Y1570197D03*
Y1580197D03*
Y1590197D03*
Y1600197D03*
Y1758228D03*
Y1768228D03*
Y1778228D03*
Y1788228D03*
Y1798228D03*
Y1808228D03*
Y1818228D03*
Y1828228D03*
Y1838228D03*
Y1848228D03*
Y1858228D03*
Y1868228D03*
Y1878228D03*
Y1888228D03*
Y1898228D03*
Y1908228D03*
Y1918228D03*
Y1928228D03*
Y1938228D03*
Y1948228D03*
X139920Y28071D03*
Y18071D03*
Y48071D03*
Y38071D03*
Y78071D03*
Y68071D03*
Y98071D03*
Y88071D03*
Y128071D03*
Y118071D03*
Y108071D03*
Y148071D03*
Y138071D03*
Y178071D03*
Y168071D03*
Y158071D03*
Y198071D03*
Y188071D03*
Y208071D03*
Y366102D03*
Y396102D03*
Y386102D03*
Y376102D03*
Y416102D03*
Y406102D03*
Y436102D03*
Y426102D03*
Y466102D03*
Y456102D03*
Y446102D03*
Y486102D03*
Y476102D03*
Y516102D03*
Y506102D03*
Y496102D03*
Y536102D03*
Y526102D03*
Y556102D03*
Y546102D03*
Y734134D03*
Y724134D03*
Y714134D03*
Y754134D03*
Y744134D03*
Y774134D03*
Y764134D03*
Y804134D03*
Y794134D03*
Y784134D03*
Y824134D03*
Y814134D03*
Y854134D03*
Y844134D03*
Y834134D03*
Y874134D03*
Y864134D03*
Y904134D03*
Y894134D03*
Y884134D03*
Y1072165D03*
Y1062165D03*
Y1092165D03*
Y1082165D03*
Y1112165D03*
Y1102165D03*
Y1142165D03*
Y1162165D03*
Y1152165D03*
Y1192165D03*
Y1182165D03*
Y1172165D03*
Y1212165D03*
Y1202165D03*
Y1242165D03*
Y1232165D03*
Y1222165D03*
Y1252165D03*
Y1410197D03*
Y1430197D03*
Y1420197D03*
Y1460197D03*
Y1450197D03*
Y1440197D03*
Y1480197D03*
Y1470197D03*
Y1500197D03*
Y1490197D03*
Y1530197D03*
Y1520197D03*
Y1510197D03*
Y1550197D03*
Y1540197D03*
Y1580197D03*
Y1570197D03*
Y1560197D03*
Y1600197D03*
Y1590197D03*
Y1768228D03*
Y1758228D03*
Y1798228D03*
Y1788228D03*
Y1778228D03*
Y1818228D03*
Y1808228D03*
Y1838228D03*
Y1828228D03*
Y1868228D03*
Y1858228D03*
Y1848228D03*
Y1888228D03*
Y1878228D03*
Y1918228D03*
Y1908228D03*
Y1898228D03*
Y1938228D03*
Y1928228D03*
Y1948228D03*
G54D34*
X64979Y171500D03*
X54979Y176500D03*
X64979Y181500D03*
Y191500D03*
Y201500D03*
X54979Y186500D03*
Y196500D03*
Y206500D03*
X64979Y244500D03*
X54979Y249500D03*
X64979Y254500D03*
Y264500D03*
Y274500D03*
X54979Y259500D03*
Y269500D03*
Y279500D03*
X64979Y380500D03*
Y390500D03*
X54979Y385500D03*
Y395500D03*
X64979Y400500D03*
Y410500D03*
X54979Y405500D03*
X189762Y73105D03*
X190289Y152050D03*
X190357Y247568D03*
X190817Y331786D03*
X189761Y421732D03*
X190553Y506517D03*
X192888Y598130D03*
X190816Y681645D03*
X191846Y774526D03*
X191606Y856244D03*
X196311Y947202D03*
X191250Y1122856D03*
X191342Y1206233D03*
X191846Y1299104D03*
X190552Y1380966D03*
X189463Y1474162D03*
X191079Y1557277D03*
X192143Y1648177D03*
X191607Y1731351D03*
X191530Y1823227D03*
X190289Y1900420D03*
X192125Y1998730D03*
X191530Y2043388D03*
X203542Y73105D03*
X204069Y152050D03*
X204137Y247568D03*
X204597Y331786D03*
X203541Y421732D03*
X204333Y506517D03*
X206668Y598130D03*
X204596Y681645D03*
X205626Y774526D03*
X205386Y856244D03*
X210091Y947202D03*
X205030Y1122856D03*
X205122Y1206233D03*
X205626Y1299104D03*
X204332Y1380966D03*
X203243Y1474162D03*
X204859Y1557277D03*
X205923Y1648177D03*
X205387Y1731351D03*
X205310Y1823227D03*
X204069Y1900420D03*
X205905Y1998730D03*
X205310Y2043388D03*
G54D32*
X23402Y1668874D03*
Y1685410D03*
Y1701945D03*
Y1718480D03*
Y1735016D03*
Y1751551D03*
Y1768087D03*
Y1784622D03*
Y1817693D03*
Y1801158D03*
X45056Y1668874D03*
Y1768087D03*
Y1817693D03*
G54D23*
X30473Y137440D03*
X30197Y305027D03*
Y352271D03*
X30473Y1855008D03*
Y1890441D03*
Y1937007D03*
Y1972440D03*
Y2012007D03*
Y2047440D03*
G54D33*
X45411Y505996D03*
Y568004D03*
Y1564000D03*
Y1626008D03*
G54D31*
X20468Y696341D03*
G54D37*
X307087Y2043503D03*
Y1693503D03*
Y1343503D03*
Y827164D03*
Y477164D03*
Y127164D03*
G54D24*
X307086Y308267D03*
G54D21*
X29979Y30500D03*
Y166500D03*
Y211500D03*
Y239500D03*
Y284500D03*
Y375500D03*
Y420500D03*
G54D26*
X373385Y32520D03*
Y207520D03*
Y382520D03*
X373386Y557520D03*
Y732520D03*
X373385Y907520D03*
Y1082520D03*
Y1257520D03*
Y1432520D03*
Y1607520D03*
Y1782520D03*
G54D25*
X359842Y78780D03*
Y253780D03*
Y428779D03*
Y603779D03*
Y778780D03*
Y953780D03*
Y1128779D03*
Y1303780D03*
Y1478780D03*
Y1653780D03*
Y1828779D03*
Y2003780D03*
G54D22*
X30254Y514500D03*
Y559500D03*
Y1572504D03*
Y1617504D03*
%LPD*%
G75*
G54D10*
X25219Y18752D03*
X3001Y52034D03*
Y100034D03*
Y150034D03*
Y200034D03*
Y250034D03*
Y300034D03*
Y350034D03*
Y400034D03*
Y450034D03*
Y500034D03*
Y550034D03*
Y600034D03*
Y650034D03*
Y700034D03*
Y750034D03*
Y800034D03*
Y850034D03*
Y900034D03*
Y950034D03*
Y1000034D03*
Y1050034D03*
Y1100034D03*
Y1150034D03*
Y1200034D03*
Y1250034D03*
Y1300034D03*
Y1350034D03*
Y1400034D03*
Y1450034D03*
Y1500034D03*
Y1550034D03*
X3006Y1594602D03*
X3012Y1610165D03*
X3001Y1650034D03*
Y1700034D03*
Y1750034D03*
Y1800034D03*
Y1850034D03*
Y1900034D03*
Y1950034D03*
Y2000034D03*
Y2050034D03*
X49441Y1238962D03*
X45581Y1278420D03*
X45413Y1283724D03*
X45244Y1289067D03*
X45350Y1299697D03*
X45267Y1294203D03*
X45281Y1310893D03*
X45244Y1305787D03*
X46980Y1325843D03*
Y1315843D03*
Y1320843D03*
Y1330843D03*
Y1345843D03*
Y1340843D03*
X26833Y2067866D03*
X70865Y897750D03*
X70340Y1328203D03*
X61866Y1342104D03*
X75219Y18752D03*
X93223Y417736D03*
X94347Y421562D03*
X82763Y1060051D03*
X76833Y2067866D03*
X114498Y396207D03*
X112503Y1115860D03*
X100719Y1312810D03*
Y1324810D03*
Y1346065D03*
X109991Y2083607D03*
X125219Y3002D03*
X144878Y1738861D03*
X161339Y88108D03*
X168975Y265783D03*
X165975D03*
X168975Y296140D03*
Y286803D03*
Y276298D03*
X165975D03*
Y286803D03*
Y296140D03*
X168975Y312307D03*
Y303868D03*
X165975D03*
Y312307D03*
X161517Y436119D03*
X157272Y604773D03*
X160272D03*
X157272Y633416D03*
Y613574D03*
Y624079D03*
X160272D03*
Y613574D03*
Y633416D03*
X157272Y641144D03*
Y649583D03*
X160272D03*
Y641144D03*
X161479Y784141D03*
X163699Y972924D03*
X166699D03*
X163699Y983439D03*
Y993944D03*
X166699D03*
Y983439D03*
X163424Y1011298D03*
Y1003570D03*
Y1019737D03*
X166424D03*
Y1003570D03*
Y1011298D03*
X158456Y1129045D03*
X158749Y1307733D03*
X155749D03*
X158749Y1328753D03*
Y1318248D03*
X155749D03*
Y1328753D03*
X158749Y1354257D03*
Y1338090D03*
Y1345818D03*
X155749D03*
Y1338090D03*
Y1354257D03*
X158618Y1399448D03*
X164037Y1400226D03*
X170351Y1401324D03*
X161492Y1667763D03*
Y1657248D03*
X158492D03*
Y1667763D03*
X161492Y1695333D03*
Y1687605D03*
Y1678268D03*
X158492D03*
Y1687605D03*
Y1695333D03*
X161492Y1703772D03*
X158492D03*
X163257Y1737619D03*
X150309Y1737009D03*
X168151Y1739208D03*
X165782Y1732903D03*
X156183Y1735240D03*
X161844Y1828225D03*
X159991Y2083607D03*
X175219Y3002D03*
X176083Y1402321D03*
X173394Y1736051D03*
X217732Y153964D03*
Y170131D03*
Y161692D03*
Y164692D03*
Y173131D03*
Y156964D03*
X219214Y1287272D03*
Y1301975D03*
X219349Y1308924D03*
X219214Y1294491D03*
X219178Y1324285D03*
Y1332321D03*
Y1316842D03*
Y1339840D03*
X209991Y2083607D03*
X225219Y3002D03*
X238741Y153964D03*
X227700D03*
X238741Y170131D03*
Y161692D03*
X227700Y170131D03*
Y161692D03*
Y164692D03*
Y173131D03*
X238741Y164692D03*
Y173131D03*
X227700Y156964D03*
X238741D03*
X239746Y407393D03*
Y396878D03*
Y417898D03*
Y399878D03*
Y410393D03*
Y420898D03*
X234012Y754782D03*
X237012D03*
X234012Y762510D03*
Y770949D03*
X237012D03*
Y762510D03*
X241396Y862887D03*
Y855159D03*
Y871326D03*
X238396D03*
Y855159D03*
Y862887D03*
X235709Y1124900D03*
Y1135415D03*
X232709D03*
Y1124900D03*
X242677Y1135415D03*
Y1124900D03*
X235709Y1145920D03*
X232709D03*
X242677D03*
X226642Y1287272D03*
X222214D03*
X229642D03*
X226642Y1301975D03*
X235465D03*
X226777Y1308924D03*
X235600D03*
X242961Y1301975D03*
X243096Y1308924D03*
X226642Y1294491D03*
X235465D03*
X242961D03*
X222214D03*
X222349Y1308924D03*
X222214Y1301975D03*
X238465Y1294491D03*
X229642D03*
X238600Y1308924D03*
X229777D03*
X238465Y1301975D03*
X229642D03*
X226606Y1324285D03*
X235429D03*
X226606Y1332321D03*
X235429D03*
X242925Y1324285D03*
Y1332321D03*
X226606Y1316842D03*
X235429D03*
X242925D03*
X222178D03*
Y1332321D03*
Y1324285D03*
X238429Y1316842D03*
X229606D03*
X238429Y1332321D03*
X229606D03*
X238429Y1324285D03*
X229606D03*
X226606Y1339840D03*
X235429D03*
X242925D03*
X222178D03*
X238429D03*
X229606D03*
X226573Y2031480D03*
X236541D03*
X226573Y2020965D03*
X236541D03*
X242582D03*
Y2031480D03*
X231541Y2020965D03*
X221573D03*
X231541Y2031480D03*
X221573D03*
X226573Y2059050D03*
X236541Y2051322D03*
Y2059050D03*
X226573Y2041985D03*
Y2051322D03*
X236541Y2041985D03*
X242582Y2059050D03*
Y2051322D03*
Y2041985D03*
X231541D03*
X221573Y2051322D03*
Y2041985D03*
X231541Y2059050D03*
Y2051322D03*
X221573Y2059050D03*
X236541Y2067489D03*
X226573D03*
X242582D03*
X221573D03*
X231541D03*
X256566Y54944D03*
X264104D03*
X256566Y45572D03*
X264104D03*
Y48572D03*
X256566D03*
Y65449D03*
X264104D03*
Y57944D03*
X256566D03*
X264104Y68449D03*
X256566D03*
X256861Y153964D03*
X248083D03*
X256861Y170131D03*
Y161692D03*
X248083Y170131D03*
Y161692D03*
Y164692D03*
Y173131D03*
X256861Y164692D03*
Y173131D03*
X248083Y156964D03*
X256861D03*
X264596Y221664D03*
X252818D03*
X255818D03*
X261596D03*
X264596Y242684D03*
Y232179D03*
X252818Y242684D03*
Y232179D03*
X255818D03*
Y242684D03*
X261596Y232179D03*
Y242684D03*
X264596Y268188D03*
Y259749D03*
Y252021D03*
X252818Y268188D03*
Y252021D03*
Y259749D03*
X255818D03*
Y252021D03*
Y268188D03*
X261596Y252021D03*
Y259749D03*
Y268188D03*
X266040Y407146D03*
Y396631D03*
Y417651D03*
X257572Y396630D03*
Y407145D03*
X248714Y407536D03*
Y397021D03*
X257572Y417650D03*
X248714Y418041D03*
Y400021D03*
Y410536D03*
X257572Y410145D03*
Y399630D03*
X266040Y399631D03*
Y410146D03*
X248714Y421041D03*
X257572Y420650D03*
X266040Y420651D03*
X267166Y581440D03*
Y572639D03*
X264166D03*
Y581440D03*
X267166Y609010D03*
Y601282D03*
Y591945D03*
X264166D03*
Y601282D03*
Y609010D03*
X267166Y617449D03*
X264166D03*
X243980Y754782D03*
X255021D03*
X258021D03*
X246980D03*
X243980Y762510D03*
Y770949D03*
X255021Y762510D03*
Y770949D03*
X258021D03*
Y762510D03*
X246980Y770949D03*
Y762510D03*
X253174Y855159D03*
Y862887D03*
Y871326D03*
X250174D03*
Y862887D03*
Y855159D03*
X265766Y949344D03*
X262766D03*
X265766Y967106D03*
Y959859D03*
X265621Y974386D03*
X262621D03*
X262766Y959859D03*
Y967106D03*
X265621Y990553D03*
Y982114D03*
X262621D03*
Y990553D03*
X263473Y1124613D03*
Y1135128D03*
X245677Y1124900D03*
Y1135415D03*
X254433Y1135271D03*
Y1124756D03*
X251433D03*
Y1135271D03*
X260473Y1135128D03*
Y1124613D03*
X263473Y1145633D03*
X245677Y1145920D03*
X254433Y1145776D03*
X251433D03*
X260473Y1145633D03*
X259581Y1272430D03*
Y1282945D03*
X256581D03*
Y1272430D03*
X267622D03*
Y1282945D03*
X245961Y1294491D03*
X246096Y1308924D03*
X245961Y1301975D03*
X259581Y1293450D03*
Y1302787D03*
Y1310515D03*
X256581D03*
Y1302787D03*
Y1293450D03*
X267622Y1310515D03*
Y1302787D03*
Y1293450D03*
X245925Y1316842D03*
Y1332321D03*
Y1324285D03*
X259581Y1318954D03*
X256581D03*
X267622D03*
X245925Y1339840D03*
X260939Y1548010D03*
Y1534139D03*
Y1541055D03*
X263939D03*
Y1534139D03*
Y1548010D03*
X258564Y1621823D03*
X261564D03*
X258564Y1642843D03*
Y1632338D03*
X261564D03*
Y1642843D03*
X258564Y1668347D03*
Y1659908D03*
Y1652180D03*
X261564D03*
Y1659908D03*
Y1668347D03*
X262759Y1697613D03*
Y1676593D03*
Y1687108D03*
X251718Y1697613D03*
Y1687108D03*
Y1676593D03*
X254718D03*
Y1687108D03*
X265759D03*
Y1676593D03*
X254718Y1697613D03*
X265759D03*
X262498Y1722140D03*
X262759Y1714678D03*
Y1706950D03*
X251457Y1722140D03*
X251718Y1714678D03*
Y1706950D03*
X265759D03*
X254718D03*
Y1714678D03*
X265759D03*
X265498Y1722140D03*
X254457D03*
X261639Y1819074D03*
Y1812119D03*
Y1805203D03*
X253468Y1819074D03*
Y1812119D03*
Y1805203D03*
X267396Y1812122D03*
Y1805206D03*
Y1819077D03*
X250468Y1805203D03*
Y1812119D03*
Y1819074D03*
X258639Y1805203D03*
Y1812119D03*
Y1819074D03*
X261459Y1826219D03*
X253288D03*
X261459Y1840090D03*
Y1833135D03*
X253288D03*
Y1840090D03*
X250288D03*
Y1833135D03*
X267037Y1840093D03*
Y1833138D03*
X258459Y1833135D03*
Y1840090D03*
X267037Y1826222D03*
X250288Y1826219D03*
X258459D03*
X247582Y2031480D03*
Y2020965D03*
X260337D03*
Y2031480D03*
X267115Y2020965D03*
Y2031480D03*
X255337D03*
Y2020965D03*
X247582Y2041985D03*
Y2051322D03*
Y2059050D03*
X260337Y2051322D03*
Y2059050D03*
Y2041985D03*
X267115D03*
Y2059050D03*
Y2051322D03*
X255337Y2041985D03*
Y2059050D03*
Y2051322D03*
X260337Y2067489D03*
X247582D03*
X267115D03*
X255337D03*
X259991Y2083607D03*
X275219Y3002D03*
X288102Y54944D03*
Y45572D03*
X271572Y54944D03*
X279754D03*
X271572Y45572D03*
X279754D03*
Y48572D03*
X271572D03*
X288102D03*
Y65449D03*
X271572D03*
X279754D03*
Y57944D03*
X271572D03*
X288102D03*
X279754Y68449D03*
X271572D03*
X288102D03*
X274531Y407289D03*
Y396774D03*
Y417794D03*
Y399774D03*
Y410289D03*
Y420794D03*
X289569Y532762D03*
Y516595D03*
Y524323D03*
X278944Y581440D03*
Y572639D03*
X275944D03*
Y581440D03*
X278944Y601282D03*
Y609010D03*
Y591945D03*
X275944D03*
Y609010D03*
Y601282D03*
X278944Y617449D03*
X275944D03*
X277544Y949344D03*
X274544D03*
X277544Y967106D03*
Y959859D03*
X277399Y974386D03*
X274399D03*
X274544Y959859D03*
Y967106D03*
X277399Y990553D03*
Y982114D03*
X274399D03*
Y990553D03*
X272821Y1124471D03*
Y1134986D03*
X269821D03*
Y1124471D03*
X272821Y1145491D03*
X269821D03*
X284182Y1184455D03*
Y1192183D03*
X287182D03*
Y1184455D03*
X284182Y1200622D03*
X287182D03*
X270622Y1282945D03*
Y1272430D03*
Y1293450D03*
Y1302787D03*
Y1310515D03*
Y1318954D03*
X275400Y1548190D03*
X268534Y1548010D03*
X282995Y1548190D03*
X275400Y1534319D03*
Y1541235D03*
X268534Y1534139D03*
Y1541055D03*
X282995Y1534319D03*
Y1541235D03*
X285995D03*
Y1534319D03*
X271534Y1541055D03*
Y1534139D03*
X278400Y1541235D03*
Y1534319D03*
X285995Y1548190D03*
X271534Y1548010D03*
X278400Y1548190D03*
X270342Y1621823D03*
X273342D03*
X270342Y1642843D03*
Y1632338D03*
X273342D03*
Y1642843D03*
X270342Y1668347D03*
Y1652180D03*
Y1659908D03*
X273342D03*
Y1652180D03*
Y1668347D03*
X270396Y1819077D03*
Y1805206D03*
Y1812122D03*
X270037Y1826222D03*
Y1833138D03*
Y1840093D03*
X272115Y2031480D03*
Y2020965D03*
Y2051322D03*
Y2059050D03*
Y2041985D03*
Y2067489D03*
X308057Y248863D03*
X306267Y241010D03*
X314940Y252083D03*
X300537Y516309D03*
X307966Y516419D03*
Y524147D03*
X300537Y524037D03*
Y532476D03*
X307966Y532586D03*
X292569Y524323D03*
Y516595D03*
Y532762D03*
X304966Y532586D03*
X297537Y532476D03*
Y524037D03*
X304966Y524147D03*
Y516419D03*
X297537Y516309D03*
X313791Y532871D03*
Y516704D03*
Y524432D03*
X315187Y652457D03*
X304146D03*
X307146D03*
X315187Y661258D03*
X304146D03*
Y681100D03*
X315187D03*
Y671763D03*
X304146D03*
X307146D03*
Y681100D03*
Y661258D03*
X315187Y688828D03*
X304146D03*
Y697267D03*
X315187D03*
X307146D03*
Y688828D03*
X310194Y1020657D03*
X310078Y1007303D03*
X310274Y1001286D03*
X310143Y1014094D03*
X307143D03*
X307274Y1001286D03*
X307078Y1007303D03*
X307194Y1020657D03*
X310129Y1027081D03*
X309999Y1033718D03*
X306999D03*
X307129Y1027081D03*
X309678Y1053262D03*
X312527Y1162266D03*
X309159Y1184526D03*
Y1192254D03*
X300691Y1184526D03*
X292721Y1184312D03*
Y1192040D03*
X300691Y1192254D03*
X303691D03*
X295721Y1192040D03*
Y1184312D03*
X303691Y1184526D03*
X312159Y1192254D03*
Y1184526D03*
X312698Y1172804D03*
X309159Y1200693D03*
X300691D03*
X292721Y1200479D03*
X295721D03*
X303691Y1200693D03*
X312159D03*
X312823Y1472957D03*
X312464Y1480102D03*
X312823Y1466002D03*
Y1459086D03*
X295715Y1480099D03*
X295895Y1472954D03*
X304066D03*
X303886Y1480099D03*
X295895Y1459083D03*
Y1465999D03*
X304066D03*
Y1459083D03*
X301066D03*
Y1465999D03*
X292895D03*
Y1459083D03*
X300886Y1480099D03*
X301066Y1472954D03*
X292895D03*
X292715Y1480099D03*
X309823Y1459086D03*
Y1466002D03*
X309464Y1480102D03*
X309823Y1472957D03*
X312464Y1493973D03*
Y1487018D03*
X295715Y1487015D03*
Y1493970D03*
X303886D03*
Y1487015D03*
X300886D03*
Y1493970D03*
X292715D03*
Y1487015D03*
X309464Y1487018D03*
Y1493973D03*
X312077Y1575871D03*
X292614Y1864565D03*
X295754Y1917148D03*
X303349D03*
X295754Y1910232D03*
X303349D03*
X310215Y1910412D03*
X314810D03*
X307215D03*
X300349Y1910232D03*
X292754D03*
X300349Y1917148D03*
X292754D03*
X310215Y1917328D03*
X295754Y1924103D03*
X303349D03*
X310215Y1924283D03*
X307215D03*
X314810D03*
X300349Y1924103D03*
X292754D03*
X307215Y1917328D03*
X314810D03*
X309991Y2083607D03*
X325219Y3002D03*
X331403Y51409D03*
X333889Y56021D03*
X338227Y61559D03*
X320961Y250105D03*
X332775Y318634D03*
X332693Y311980D03*
X329693D03*
X329775Y318634D03*
X332775Y335272D03*
Y342461D03*
Y325935D03*
X329775D03*
Y342461D03*
Y335272D03*
X332685Y348655D03*
X329685D03*
X335522Y404033D03*
X323313Y418313D03*
X326196Y413982D03*
X328950Y409216D03*
X320980Y423225D03*
X325139Y516632D03*
Y524360D03*
X316791Y524432D03*
Y516704D03*
Y532871D03*
X325139Y532799D03*
X322139D03*
Y524360D03*
Y516632D03*
X319305Y582111D03*
X317724Y588250D03*
X320380Y576491D03*
X321742Y599041D03*
X318187Y652457D03*
Y671763D03*
Y681100D03*
Y661258D03*
Y697267D03*
Y688828D03*
X331568Y752967D03*
X339012Y752859D03*
X329336Y762693D03*
X334010Y758588D03*
X327524Y758020D03*
X324098Y946104D03*
X326646Y939788D03*
X328583Y933262D03*
X321425Y951577D03*
X321235Y1020657D03*
X321315Y1001286D03*
X321119Y1007303D03*
X321184Y1014094D03*
X318184D03*
X318119Y1007303D03*
X318315Y1001286D03*
X318235Y1020657D03*
X321170Y1027081D03*
X321040Y1033718D03*
X318040D03*
X318170Y1027081D03*
X324246Y1051786D03*
X335677Y1048904D03*
X317592Y1053050D03*
X317936Y1192253D03*
Y1184525D03*
X320936D03*
Y1192253D03*
X323403Y1172804D03*
X317936Y1200692D03*
X320936D03*
X327452Y1279447D03*
X321978Y1282086D03*
X329619Y1284016D03*
X327932Y1289221D03*
X334646Y1400804D03*
X323720Y1570924D03*
X333474Y1566686D03*
X335963Y1573797D03*
X317810Y1910412D03*
X332399Y1926787D03*
X317810Y1917328D03*
Y1924283D03*
X348289Y50863D03*
X345089Y56190D03*
X340373Y51579D03*
X343816Y318634D03*
X343734Y311980D03*
X340734D03*
X340816Y318634D03*
X343816Y335272D03*
Y342461D03*
Y325935D03*
X340816D03*
Y342461D03*
Y335272D03*
X362236Y324983D03*
X343726Y348655D03*
X340726D03*
X342097Y401684D03*
X344109Y751809D03*
X345578Y1047844D03*
X344130Y1401670D03*
X345537Y1916558D03*
X344402Y1911123D03*
X340336Y1922409D03*
X359991Y2083607D03*
X375219Y3002D03*
X374681Y1365620D03*
X402512Y17108D03*
Y67108D03*
Y117108D03*
Y167108D03*
Y217108D03*
Y267108D03*
Y317108D03*
Y367108D03*
Y417108D03*
Y467108D03*
Y517108D03*
Y567108D03*
Y617108D03*
Y667108D03*
Y717108D03*
Y767108D03*
Y817108D03*
Y867108D03*
Y917108D03*
Y967108D03*
Y1017108D03*
Y1067108D03*
Y1117108D03*
Y1167108D03*
Y1217108D03*
Y1267108D03*
Y1317108D03*
Y1367108D03*
Y1417108D03*
Y1467108D03*
Y1517108D03*
Y1567108D03*
Y1617108D03*
Y1667108D03*
Y1717108D03*
Y1767108D03*
Y1817108D03*
Y1867108D03*
Y1917108D03*
Y1967108D03*
Y2017108D03*
Y2067108D03*
G54D20*
G01X-723776Y2987387D02*
Y-376795D01*
Y-489221D01*
X1782976D01*
Y-376795D01*
Y2987387D01*
X-723776D01*
G01X-4000Y-62500D02*
Y-137500D01*
X496000D01*
Y-62500D01*
X-4000D01*
G01X8000Y-127500D02*
Y-132500D01*
G01X6543Y-127500D02*
X9457D01*
G01X14367Y-132500D02*
X11833D01*
Y-127500D01*
X14367D01*
G01X13353Y-129917D02*
X11833D01*
G01X16933Y-127500D02*
Y-132500D01*
X19467D01*
G01X23300Y-132667D02*
X23173Y-132583D01*
Y-132417D01*
X23300Y-132333D01*
X23427Y-132417D01*
Y-132583D01*
X23300Y-132667D01*
G01Y-130417D02*
X23173Y-130333D01*
Y-130167D01*
X23300Y-130083D01*
X23427Y-130167D01*
Y-130333D01*
X23300Y-130417D01*
G01X28083Y-134167D02*
X27450Y-133333D01*
X27133Y-132500D01*
Y-129167D01*
X27450Y-128333D01*
X28083Y-127500D01*
G01X33500D02*
X32993Y-127667D01*
X32613Y-128083D01*
X32360Y-128583D01*
X32170Y-129250D01*
X32107Y-130000D01*
X32170Y-130750D01*
X32360Y-131417D01*
X32613Y-131917D01*
X32993Y-132333D01*
X33500Y-132500D01*
X34007Y-132333D01*
X34387Y-131917D01*
X34640Y-131417D01*
X34830Y-130750D01*
X34893Y-130000D01*
X34830Y-129250D01*
X34640Y-128583D01*
X34387Y-128083D01*
X34007Y-127667D01*
X33500Y-127500D01*
G01X37207Y-131500D02*
X37587Y-132083D01*
X38093Y-132417D01*
X38663Y-132500D01*
X39170Y-132417D01*
X39677Y-132000D01*
X39993Y-131500D01*
X40057Y-131000D01*
X39930Y-130417D01*
X39487Y-130000D01*
X39043Y-129833D01*
X38473D01*
G01X39043D02*
X39423Y-129583D01*
X39740Y-129167D01*
X39867Y-128667D01*
X39740Y-128167D01*
X39423Y-127750D01*
X38853Y-127500D01*
X38283Y-127583D01*
X37713Y-127917D01*
G01X44017Y-134167D02*
X44650Y-133333D01*
X44967Y-132500D01*
Y-129167D01*
X44650Y-128333D01*
X44017Y-127500D01*
G01X47407Y-131500D02*
X47787Y-132083D01*
X48293Y-132417D01*
X48863Y-132500D01*
X49370Y-132417D01*
X49877Y-132000D01*
X50193Y-131500D01*
X50257Y-131000D01*
X50130Y-130417D01*
X49687Y-130000D01*
X49243Y-129833D01*
X48673D01*
G01X49243D02*
X49623Y-129583D01*
X49940Y-129167D01*
X50067Y-128667D01*
X49940Y-128167D01*
X49623Y-127750D01*
X49053Y-127500D01*
X48483Y-127583D01*
X47913Y-127917D01*
G01X52697Y-128333D02*
X53077Y-127833D01*
X53520Y-127583D01*
X54027Y-127500D01*
X54660Y-127667D01*
X55103Y-128083D01*
X55230Y-128583D01*
X55167Y-129083D01*
X54913Y-129500D01*
X53647Y-130333D01*
X53077Y-130917D01*
X52697Y-131750D01*
X52570Y-132500D01*
X55230D01*
G01X58873D02*
X59000Y-131417D01*
X59190Y-130500D01*
X59443Y-129667D01*
X59760Y-128750D01*
X60267Y-127500D01*
X57733D01*
G01X63277Y-130833D02*
X64923D01*
G01X67997Y-128333D02*
X68377Y-127833D01*
X68820Y-127583D01*
X69327Y-127500D01*
X69960Y-127667D01*
X70403Y-128083D01*
X70530Y-128583D01*
X70467Y-129083D01*
X70213Y-129500D01*
X68947Y-130333D01*
X68377Y-130917D01*
X67997Y-131750D01*
X67870Y-132500D01*
X70530D01*
G01X72907Y-131500D02*
X73287Y-132083D01*
X73793Y-132417D01*
X74363Y-132500D01*
X74870Y-132417D01*
X75377Y-132000D01*
X75693Y-131500D01*
X75757Y-131000D01*
X75630Y-130417D01*
X75187Y-130000D01*
X74743Y-129833D01*
X74173D01*
G01X74743D02*
X75123Y-129583D01*
X75440Y-129167D01*
X75567Y-128667D01*
X75440Y-128167D01*
X75123Y-127750D01*
X74553Y-127500D01*
X73983Y-127583D01*
X73413Y-127917D01*
G01X80160Y-132500D02*
Y-127500D01*
X77817Y-131083D01*
X80983D01*
G01X83107Y-131750D02*
X83487Y-132167D01*
X83930Y-132417D01*
X84500Y-132500D01*
X85070Y-132333D01*
X85513Y-132000D01*
X85830Y-131417D01*
X85893Y-130750D01*
X85767Y-130083D01*
X85450Y-129667D01*
X85007Y-129333D01*
X84563Y-129250D01*
X84120Y-129333D01*
X83550Y-129667D01*
X83740Y-127500D01*
X85450D01*
G01X93497Y-132500D02*
Y-127500D01*
X95903D01*
G01X95017Y-129917D02*
X93497D01*
G01X98217Y-132500D02*
X99800Y-127500D01*
X101383Y-132500D01*
G01X100813Y-130750D02*
X98787D01*
G01X103570Y-132500D02*
X106230Y-127500D01*
G01X103570D02*
X106230Y-132500D01*
G01X110000Y-132667D02*
X109873Y-132583D01*
Y-132417D01*
X110000Y-132333D01*
X110127Y-132417D01*
Y-132583D01*
X110000Y-132667D01*
G01Y-130417D02*
X109873Y-130333D01*
Y-130167D01*
X110000Y-130083D01*
X110127Y-130167D01*
Y-130333D01*
X110000Y-130417D01*
G01X114783Y-134167D02*
X114150Y-133333D01*
X113833Y-132500D01*
Y-129167D01*
X114150Y-128333D01*
X114783Y-127500D01*
G01X120200D02*
X119693Y-127667D01*
X119313Y-128083D01*
X119060Y-128583D01*
X118870Y-129250D01*
X118807Y-130000D01*
X118870Y-130750D01*
X119060Y-131417D01*
X119313Y-131917D01*
X119693Y-132333D01*
X120200Y-132500D01*
X120707Y-132333D01*
X121087Y-131917D01*
X121340Y-131417D01*
X121530Y-130750D01*
X121593Y-130000D01*
X121530Y-129250D01*
X121340Y-128583D01*
X121087Y-128083D01*
X120707Y-127667D01*
X120200Y-127500D01*
G01X123907Y-131500D02*
X124287Y-132083D01*
X124793Y-132417D01*
X125363Y-132500D01*
X125870Y-132417D01*
X126377Y-132000D01*
X126693Y-131500D01*
X126757Y-131000D01*
X126630Y-130417D01*
X126187Y-130000D01*
X125743Y-129833D01*
X125173D01*
G01X125743D02*
X126123Y-129583D01*
X126440Y-129167D01*
X126567Y-128667D01*
X126440Y-128167D01*
X126123Y-127750D01*
X125553Y-127500D01*
X124983Y-127583D01*
X124413Y-127917D01*
G01X130717Y-134167D02*
X131350Y-133333D01*
X131667Y-132500D01*
Y-129167D01*
X131350Y-128333D01*
X130717Y-127500D01*
G01X134107Y-131500D02*
X134487Y-132083D01*
X134993Y-132417D01*
X135563Y-132500D01*
X136070Y-132417D01*
X136577Y-132000D01*
X136893Y-131500D01*
X136957Y-131000D01*
X136830Y-130417D01*
X136387Y-130000D01*
X135943Y-129833D01*
X135373D01*
G01X135943D02*
X136323Y-129583D01*
X136640Y-129167D01*
X136767Y-128667D01*
X136640Y-128167D01*
X136323Y-127750D01*
X135753Y-127500D01*
X135183Y-127583D01*
X134613Y-127917D01*
G01X139523Y-131917D02*
X139967Y-132333D01*
X140473Y-132500D01*
X140980Y-132333D01*
X141423Y-131833D01*
X141740Y-131083D01*
X141867Y-130333D01*
Y-129417D01*
X141740Y-128667D01*
X141423Y-128000D01*
X141043Y-127667D01*
X140600Y-127500D01*
X140093Y-127667D01*
X139713Y-128000D01*
X139460Y-128500D01*
X139333Y-129167D01*
X139460Y-129750D01*
X139777Y-130333D01*
X140157Y-130667D01*
X140600Y-130750D01*
X141107Y-130583D01*
X141487Y-130167D01*
X141867Y-129417D01*
G01X145573Y-132500D02*
X145700Y-131417D01*
X145890Y-130500D01*
X146143Y-129667D01*
X146460Y-128750D01*
X146967Y-127500D01*
X144433D01*
G01X149977Y-130833D02*
X151623D01*
G01X154507Y-131500D02*
X154887Y-132083D01*
X155393Y-132417D01*
X155963Y-132500D01*
X156470Y-132417D01*
X156977Y-132000D01*
X157293Y-131500D01*
X157357Y-131000D01*
X157230Y-130417D01*
X156787Y-130000D01*
X156343Y-129833D01*
X155773D01*
G01X156343D02*
X156723Y-129583D01*
X157040Y-129167D01*
X157167Y-128667D01*
X157040Y-128167D01*
X156723Y-127750D01*
X156153Y-127500D01*
X155583Y-127583D01*
X155013Y-127917D01*
G01X159797Y-130417D02*
X160240Y-129833D01*
X160620Y-129500D01*
X161127Y-129333D01*
X161570Y-129500D01*
X161887Y-129833D01*
X162140Y-130333D01*
X162203Y-130917D01*
X162140Y-131417D01*
X161887Y-131917D01*
X161507Y-132333D01*
X161063Y-132500D01*
X160557Y-132333D01*
X160113Y-131833D01*
X159860Y-131083D01*
X159797Y-130250D01*
X159923Y-129167D01*
X160113Y-128583D01*
X160430Y-128000D01*
X160873Y-127583D01*
X161317Y-127500D01*
X161760Y-127667D01*
X162077Y-128083D01*
G01X166100Y-132500D02*
Y-127500D01*
X165340Y-128500D01*
G01Y-132500D02*
X166860D01*
G01X171960D02*
Y-127500D01*
X169617Y-131083D01*
X172783D01*
G01X191000Y-62500D02*
Y-137500D01*
G01Y-112500D02*
X294000D01*
Y-87500D01*
G01X191000D02*
X294000D01*
G01X301507Y-122500D02*
Y-117500D01*
X302773D01*
X303280Y-117750D01*
X303660Y-118083D01*
X303977Y-118583D01*
X304230Y-119167D01*
X304293Y-120000D01*
X304230Y-120833D01*
X303977Y-121417D01*
X303660Y-121917D01*
X303280Y-122250D01*
X302773Y-122500D01*
X301507D01*
G01X306417D02*
X308000Y-117500D01*
X309583Y-122500D01*
G01X309013Y-120750D02*
X306987D01*
G01X313100Y-117500D02*
Y-122500D01*
G01X311643Y-117500D02*
X314557D01*
G01X319467Y-122500D02*
X316933D01*
Y-117500D01*
X319467D01*
G01X318453Y-119917D02*
X316933D01*
G01X323300Y-122667D02*
X323173Y-122583D01*
Y-122417D01*
X323300Y-122333D01*
X323427Y-122417D01*
Y-122583D01*
X323300Y-122667D01*
G01Y-120417D02*
X323173Y-120333D01*
Y-120167D01*
X323300Y-120083D01*
X323427Y-120167D01*
Y-120333D01*
X323300Y-120417D01*
G01X296000Y-62500D02*
Y-137500D01*
G01X294000Y-62500D02*
Y-137500D01*
G01X301633Y-97500D02*
Y-92500D01*
X303153D01*
X303660Y-92750D01*
X304040Y-93333D01*
X304167Y-94000D01*
X304040Y-94667D01*
X303723Y-95167D01*
X303153Y-95417D01*
X301633D01*
G01X306860Y-97667D02*
X309140Y-92500D01*
G01X311643Y-97500D02*
Y-92500D01*
X314557Y-97500D01*
Y-92500D01*
G01X318200Y-97667D02*
X318073Y-97583D01*
Y-97417D01*
X318200Y-97333D01*
X318327Y-97417D01*
Y-97583D01*
X318200Y-97667D01*
G01Y-95417D02*
X318073Y-95333D01*
Y-95167D01*
X318200Y-95083D01*
X318327Y-95167D01*
Y-95333D01*
X318200Y-95417D01*
G01X296000Y-112500D02*
X496000D01*
G01X301633Y-72500D02*
Y-67500D01*
X303153D01*
X303660Y-67750D01*
X304040Y-68333D01*
X304167Y-69000D01*
X304040Y-69667D01*
X303723Y-70167D01*
X303153Y-70417D01*
X301633D01*
G01X306733Y-72500D02*
Y-67500D01*
X308317D01*
X308823Y-67750D01*
X309140Y-68083D01*
X309267Y-68750D01*
X309140Y-69417D01*
X308760Y-69833D01*
X308317Y-70083D01*
X306733D01*
G01X308317D02*
X309267Y-72500D01*
G01X313100D02*
X312593Y-72417D01*
X312150Y-72083D01*
X311770Y-71583D01*
X311517Y-71000D01*
X311390Y-70333D01*
Y-69667D01*
X311517Y-69000D01*
X311770Y-68417D01*
X312150Y-67917D01*
X312593Y-67583D01*
X313100Y-67500D01*
X313607Y-67583D01*
X314050Y-67917D01*
X314430Y-68417D01*
X314683Y-69000D01*
X314810Y-69667D01*
Y-70333D01*
X314683Y-71000D01*
X314430Y-71583D01*
X314050Y-72083D01*
X313607Y-72417D01*
X313100Y-72500D01*
G01X316933Y-71500D02*
X317250Y-72000D01*
X317630Y-72333D01*
X318073Y-72500D01*
X318580Y-72333D01*
X318960Y-72000D01*
X319340Y-71500D01*
X319467Y-70833D01*
Y-67500D01*
G01X324567Y-72500D02*
X322033D01*
Y-67500D01*
X324567D01*
G01X323553Y-69917D02*
X322033D01*
G01X329793Y-67917D02*
X329413Y-67667D01*
X328970Y-67500D01*
X328463D01*
X327893Y-67750D01*
X327450Y-68167D01*
X327133Y-68667D01*
X326880Y-69500D01*
X326817Y-70250D01*
X326943Y-71000D01*
X327133Y-71500D01*
X327513Y-72000D01*
X327957Y-72333D01*
X328400Y-72500D01*
X328843D01*
X329287Y-72333D01*
X329667Y-72083D01*
X329983Y-71750D01*
G01X333500Y-67500D02*
Y-72500D01*
G01X332043Y-67500D02*
X334957D01*
G01X338600Y-72667D02*
X338473Y-72583D01*
Y-72417D01*
X338600Y-72333D01*
X338727Y-72417D01*
Y-72583D01*
X338600Y-72667D01*
G01Y-70417D02*
X338473Y-70333D01*
Y-70167D01*
X338600Y-70083D01*
X338727Y-70167D01*
Y-70333D01*
X338600Y-70417D01*
G01X296000Y-87500D02*
X496000D01*
G01X411000Y-112500D02*
Y-137500D01*
G01X416633Y-122500D02*
Y-117500D01*
X418217D01*
X418723Y-117750D01*
X419040Y-118083D01*
X419167Y-118750D01*
X419040Y-119417D01*
X418660Y-119833D01*
X418217Y-120083D01*
X416633D01*
G01X418217D02*
X419167Y-122500D01*
G01X424267D02*
X421733D01*
Y-117500D01*
X424267D01*
G01X423253Y-119917D02*
X421733D01*
G01X426517Y-117500D02*
X428100Y-122500D01*
X429683Y-117500D01*
G01X433200Y-122667D02*
X433073Y-122583D01*
Y-122417D01*
X433200Y-122333D01*
X433327Y-122417D01*
Y-122583D01*
X433200Y-122667D01*
G01Y-120417D02*
X433073Y-120333D01*
Y-120167D01*
X433200Y-120083D01*
X433327Y-120167D01*
Y-120333D01*
X433200Y-120417D01*
G01X460000Y-112500D02*
Y-137500D01*
G01X-723776Y2987387D02*
Y-376795D01*
Y-489221D01*
X1782976D01*
Y-376795D01*
Y2987387D01*
X-723776D01*
G01X6705Y-124160D02*
X7332Y-124685D01*
X8037Y-125000D01*
X8663D01*
X9290Y-124685D01*
X9760Y-124160D01*
X9995Y-123425D01*
X9838Y-122690D01*
X9447Y-122060D01*
X8742Y-121640D01*
X7802Y-121430D01*
X7253Y-121010D01*
X7018Y-120275D01*
X7175Y-119540D01*
X7567Y-119015D01*
X8115Y-118700D01*
X8663D01*
X9212Y-118910D01*
X9682Y-119435D01*
G01X13005Y-125000D02*
Y-118700D01*
G01X16295D02*
Y-125000D01*
G01Y-121850D02*
X13005D01*
G01X20010Y-118700D02*
X21890D01*
G01X20950D02*
Y-125000D01*
G01X20010D02*
X21890D01*
G01X28817D02*
X25683D01*
Y-118700D01*
X28817D01*
G01X27563Y-121745D02*
X25683D01*
G01X31748Y-125000D02*
Y-118700D01*
X35352Y-125000D01*
Y-118700D01*
G01X39693Y-126155D02*
X40007Y-124790D01*
G01X46150Y-118700D02*
Y-125000D01*
G01X44348Y-118700D02*
X47952D01*
G01X50492Y-125000D02*
X52450Y-118700D01*
X54408Y-125000D01*
G01X53703Y-122795D02*
X51197D01*
G01X57810Y-118700D02*
X59690D01*
G01X58750D02*
Y-125000D01*
G01X57810D02*
X59690D01*
G01X62700Y-118700D02*
X63797Y-125000D01*
X65050Y-118700D01*
X66303Y-125000D01*
X67400Y-118700D01*
G01X69392Y-125000D02*
X71350Y-118700D01*
X73308Y-125000D01*
G01X72603Y-122795D02*
X70097D01*
G01X75848Y-125000D02*
Y-118700D01*
X79452Y-125000D01*
Y-118700D01*
G01X88683Y-125000D02*
Y-118700D01*
X90642D01*
X91268Y-119015D01*
X91660Y-119435D01*
X91817Y-120275D01*
X91660Y-121115D01*
X91190Y-121640D01*
X90642Y-121955D01*
X88683D01*
G01X90642D02*
X91817Y-125000D01*
G01X96550Y-125210D02*
X96393Y-125105D01*
Y-124895D01*
X96550Y-124790D01*
X96707Y-124895D01*
Y-125105D01*
X96550Y-125210D01*
G01X102850Y-125000D02*
X102223Y-124895D01*
X101675Y-124475D01*
X101205Y-123845D01*
X100892Y-123110D01*
X100735Y-122270D01*
Y-121430D01*
X100892Y-120590D01*
X101205Y-119855D01*
X101675Y-119225D01*
X102223Y-118805D01*
X102850Y-118700D01*
X103477Y-118805D01*
X104025Y-119225D01*
X104495Y-119855D01*
X104808Y-120590D01*
X104965Y-121430D01*
Y-122270D01*
X104808Y-123110D01*
X104495Y-123845D01*
X104025Y-124475D01*
X103477Y-124895D01*
X102850Y-125000D01*
G01X109150Y-125210D02*
X108993Y-125105D01*
Y-124895D01*
X109150Y-124790D01*
X109307Y-124895D01*
Y-125105D01*
X109150Y-125210D01*
G01X117173Y-119225D02*
X116703Y-118910D01*
X116155Y-118700D01*
X115528D01*
X114823Y-119015D01*
X114275Y-119540D01*
X113883Y-120170D01*
X113570Y-121220D01*
X113492Y-122165D01*
X113648Y-123110D01*
X113883Y-123740D01*
X114353Y-124370D01*
X114902Y-124790D01*
X115450Y-125000D01*
X115998D01*
X116547Y-124790D01*
X117017Y-124475D01*
X117408Y-124055D01*
G01X121750Y-125210D02*
X121593Y-125105D01*
Y-124895D01*
X121750Y-124790D01*
X121907Y-124895D01*
Y-125105D01*
X121750Y-125210D01*
G01X6627Y-115000D02*
Y-108700D01*
G01X9603D02*
X6627Y-112585D01*
G01X10073Y-115000D02*
X7958Y-110800D01*
G01X12927Y-108700D02*
Y-113215D01*
X13240Y-114160D01*
X13867Y-114790D01*
X14650Y-115000D01*
X15433Y-114790D01*
X16060Y-114160D01*
X16373Y-113215D01*
Y-108700D01*
G01X22517Y-115000D02*
X19383D01*
Y-108700D01*
X22517D01*
G01X21263Y-111745D02*
X19383D01*
G01X26310Y-108700D02*
X28190D01*
G01X27250D02*
Y-115000D01*
G01X26310D02*
X28190D01*
G01X38205Y-114160D02*
X38832Y-114685D01*
X39537Y-115000D01*
X40163D01*
X40790Y-114685D01*
X41260Y-114160D01*
X41495Y-113425D01*
X41338Y-112690D01*
X40947Y-112060D01*
X40242Y-111640D01*
X39302Y-111430D01*
X38753Y-111010D01*
X38518Y-110275D01*
X38675Y-109540D01*
X39067Y-109015D01*
X39615Y-108700D01*
X40163D01*
X40712Y-108910D01*
X41182Y-109435D01*
G01X44505Y-115000D02*
Y-108700D01*
G01X47795D02*
Y-115000D01*
G01Y-111850D02*
X44505D01*
G01X50492Y-115000D02*
X52450Y-108700D01*
X54408Y-115000D01*
G01X53703Y-112795D02*
X51197D01*
G01X56948Y-115000D02*
Y-108700D01*
X60552Y-115000D01*
Y-108700D01*
G01X69705Y-115000D02*
Y-108700D01*
G01X72995D02*
Y-115000D01*
G01Y-111850D02*
X69705D01*
G01X76005Y-114160D02*
X76632Y-114685D01*
X77337Y-115000D01*
X77963D01*
X78590Y-114685D01*
X79060Y-114160D01*
X79295Y-113425D01*
X79138Y-112690D01*
X78747Y-112060D01*
X78042Y-111640D01*
X77102Y-111430D01*
X76553Y-111010D01*
X76318Y-110275D01*
X76475Y-109540D01*
X76867Y-109015D01*
X77415Y-108700D01*
X77963D01*
X78512Y-108910D01*
X78982Y-109435D01*
G01X83010Y-108700D02*
X84890D01*
G01X83950D02*
Y-115000D01*
G01X83010D02*
X84890D01*
G01X88292D02*
X90250Y-108700D01*
X92208Y-115000D01*
G01X91503Y-112795D02*
X88997D01*
G01X94748Y-115000D02*
Y-108700D01*
X98352Y-115000D01*
Y-108700D01*
G01X103320Y-111850D02*
X104887D01*
Y-113740D01*
X104417Y-114370D01*
X103868Y-114790D01*
X103085Y-115000D01*
X102302Y-114790D01*
X101753Y-114370D01*
X101283Y-113740D01*
X100970Y-113005D01*
X100813Y-112165D01*
Y-111430D01*
X100970Y-110800D01*
X101283Y-110065D01*
X101753Y-109435D01*
X102223Y-109015D01*
X102850Y-108700D01*
X103398D01*
X104025Y-108910D01*
X104495Y-109330D01*
G01X108993Y-116155D02*
X109307Y-114790D01*
G01X115450Y-108700D02*
Y-115000D01*
G01X113648Y-108700D02*
X117252D01*
G01X119792Y-115000D02*
X121750Y-108700D01*
X123708Y-115000D01*
G01X123003Y-112795D02*
X120497D01*
G01X128050Y-115000D02*
X127423Y-114895D01*
X126875Y-114475D01*
X126405Y-113845D01*
X126092Y-113110D01*
X125935Y-112270D01*
Y-111430D01*
X126092Y-110590D01*
X126405Y-109855D01*
X126875Y-109225D01*
X127423Y-108805D01*
X128050Y-108700D01*
X128677Y-108805D01*
X129225Y-109225D01*
X129695Y-109855D01*
X130008Y-110590D01*
X130165Y-111430D01*
Y-112270D01*
X130008Y-113110D01*
X129695Y-113845D01*
X129225Y-114475D01*
X128677Y-114895D01*
X128050Y-115000D01*
G01X140650D02*
Y-112165D01*
X139083Y-108700D01*
G01X142217D02*
X140650Y-112165D01*
G01X145227Y-108700D02*
Y-113215D01*
X145540Y-114160D01*
X146167Y-114790D01*
X146950Y-115000D01*
X147733Y-114790D01*
X148360Y-114160D01*
X148673Y-113215D01*
Y-108700D01*
G01X151292Y-115000D02*
X153250Y-108700D01*
X155208Y-115000D01*
G01X154503Y-112795D02*
X151997D01*
G01X157748Y-115000D02*
Y-108700D01*
X161352Y-115000D01*
Y-108700D01*
G01X30650Y-92300D02*
X28130Y-91883D01*
X25925Y-90217D01*
X24035Y-87717D01*
X22775Y-84800D01*
X22145Y-81467D01*
Y-78133D01*
X22775Y-74800D01*
X24035Y-71883D01*
X25925Y-69384D01*
X28130Y-67717D01*
X30650Y-67300D01*
X33170Y-67717D01*
X35375Y-69384D01*
X37265Y-71883D01*
X38525Y-74800D01*
X39155Y-78133D01*
Y-81467D01*
X38525Y-84800D01*
X37265Y-87717D01*
X35375Y-90217D01*
X33170Y-91883D01*
X30650Y-92300D01*
G01X33170Y-85633D02*
X36950Y-92300D01*
G01X50495Y-75634D02*
Y-87300D01*
X51755Y-90217D01*
X53645Y-91883D01*
X55850Y-92300D01*
X58055Y-91883D01*
X59945Y-90217D01*
X61205Y-87300D01*
G01Y-92300D02*
Y-75634D01*
G01X86720Y-92300D02*
Y-75634D01*
G01Y-78550D02*
X85460Y-76884D01*
X83570Y-76050D01*
X81365Y-75634D01*
X79160Y-76467D01*
X77270Y-78133D01*
X76010Y-80634D01*
X75380Y-83967D01*
X76010Y-87300D01*
X77270Y-89801D01*
X79160Y-91467D01*
X81365Y-92300D01*
X83570Y-91883D01*
X85460Y-90634D01*
X86720Y-88967D01*
G01X100895Y-92300D02*
Y-75634D01*
G01Y-79800D02*
X102155Y-77717D01*
X104045Y-76050D01*
X106565Y-75634D01*
X108770Y-76050D01*
X110660Y-77717D01*
X111605Y-80634D01*
Y-92300D01*
G01X131450Y-67300D02*
Y-92300D01*
G01X127040Y-75634D02*
X135860D01*
G01X162320Y-92300D02*
Y-75634D01*
G01Y-78550D02*
X161060Y-76884D01*
X159170Y-76050D01*
X156965Y-75634D01*
X154760Y-76467D01*
X152870Y-78133D01*
X151610Y-80634D01*
X150980Y-83967D01*
X151610Y-87300D01*
X152870Y-89801D01*
X154760Y-91467D01*
X156965Y-92300D01*
X159170Y-91883D01*
X161060Y-90634D01*
X162320Y-88967D01*
G01X6548Y-105000D02*
Y-98700D01*
X10152Y-105000D01*
Y-98700D01*
G01X14650Y-105000D02*
X14023Y-104895D01*
X13475Y-104475D01*
X13005Y-103845D01*
X12692Y-103110D01*
X12535Y-102270D01*
Y-101430D01*
X12692Y-100590D01*
X13005Y-99855D01*
X13475Y-99225D01*
X14023Y-98805D01*
X14650Y-98700D01*
X15277Y-98805D01*
X15825Y-99225D01*
X16295Y-99855D01*
X16608Y-100590D01*
X16765Y-101430D01*
Y-102270D01*
X16608Y-103110D01*
X16295Y-103845D01*
X15825Y-104475D01*
X15277Y-104895D01*
X14650Y-105000D01*
G01X20950Y-105210D02*
X20793Y-105105D01*
Y-104895D01*
X20950Y-104790D01*
X21107Y-104895D01*
Y-105105D01*
X20950Y-105210D01*
G01X27250Y-105000D02*
Y-98700D01*
X26310Y-99960D01*
G01Y-105000D02*
X28190D01*
G01X33550D02*
X34098Y-104895D01*
X34725Y-104580D01*
X35117Y-104055D01*
X35273Y-103320D01*
X35117Y-102585D01*
X34647Y-101955D01*
X33942Y-101640D01*
X33158D01*
X32688Y-101430D01*
X32297Y-100905D01*
X32140Y-100170D01*
X32375Y-99435D01*
X32923Y-98910D01*
X33550Y-98700D01*
X34177Y-98910D01*
X34725Y-99435D01*
X34960Y-100170D01*
X34803Y-100905D01*
X34412Y-101430D01*
X33942Y-101640D01*
X33158D01*
X32453Y-101955D01*
X31983Y-102585D01*
X31827Y-103320D01*
X31983Y-104055D01*
X32375Y-104580D01*
X33002Y-104895D01*
X33550Y-105000D01*
G01X39850D02*
X40398Y-104895D01*
X41025Y-104580D01*
X41417Y-104055D01*
X41573Y-103320D01*
X41417Y-102585D01*
X40947Y-101955D01*
X40242Y-101640D01*
X39458D01*
X38988Y-101430D01*
X38597Y-100905D01*
X38440Y-100170D01*
X38675Y-99435D01*
X39223Y-98910D01*
X39850Y-98700D01*
X40477Y-98910D01*
X41025Y-99435D01*
X41260Y-100170D01*
X41103Y-100905D01*
X40712Y-101430D01*
X40242Y-101640D01*
X39458D01*
X38753Y-101955D01*
X38283Y-102585D01*
X38127Y-103320D01*
X38283Y-104055D01*
X38675Y-104580D01*
X39302Y-104895D01*
X39850Y-105000D01*
G01X45993Y-106155D02*
X46307Y-104790D01*
G01X50100Y-98700D02*
X51197Y-105000D01*
X52450Y-98700D01*
X53703Y-105000D01*
X54800Y-98700D01*
G01X60317Y-105000D02*
X57183D01*
Y-98700D01*
X60317D01*
G01X59063Y-101745D02*
X57183D01*
G01X63248Y-105000D02*
Y-98700D01*
X66852Y-105000D01*
Y-98700D01*
G01X76005Y-105000D02*
Y-98700D01*
G01X79295D02*
Y-105000D01*
G01Y-101850D02*
X76005D01*
G01X81600Y-98700D02*
X82697Y-105000D01*
X83950Y-98700D01*
X85203Y-105000D01*
X86300Y-98700D01*
G01X88292Y-105000D02*
X90250Y-98700D01*
X92208Y-105000D01*
G01X91503Y-102795D02*
X88997D01*
G01X101362Y-99750D02*
X101832Y-99120D01*
X102380Y-98805D01*
X103007Y-98700D01*
X103790Y-98910D01*
X104338Y-99435D01*
X104495Y-100065D01*
X104417Y-100695D01*
X104103Y-101220D01*
X102537Y-102270D01*
X101832Y-103005D01*
X101362Y-104055D01*
X101205Y-105000D01*
X104495D01*
G01X107348D02*
Y-98700D01*
X110952Y-105000D01*
Y-98700D01*
G01X113727Y-105000D02*
Y-98700D01*
X115293D01*
X115920Y-99015D01*
X116390Y-99435D01*
X116782Y-100065D01*
X117095Y-100800D01*
X117173Y-101850D01*
X117095Y-102900D01*
X116782Y-103635D01*
X116390Y-104265D01*
X115920Y-104685D01*
X115293Y-105000D01*
X113727D01*
G01X126483D02*
Y-98700D01*
X128442D01*
X129068Y-99015D01*
X129460Y-99435D01*
X129617Y-100275D01*
X129460Y-101115D01*
X128990Y-101640D01*
X128442Y-101955D01*
X126483D01*
G01X128442D02*
X129617Y-105000D01*
G01X132627D02*
Y-98700D01*
X134193D01*
X134820Y-99015D01*
X135290Y-99435D01*
X135682Y-100065D01*
X135995Y-100800D01*
X136073Y-101850D01*
X135995Y-102900D01*
X135682Y-103635D01*
X135290Y-104265D01*
X134820Y-104685D01*
X134193Y-105000D01*
X132627D01*
G01X140650Y-105210D02*
X140493Y-105105D01*
Y-104895D01*
X140650Y-104790D01*
X140807Y-104895D01*
Y-105105D01*
X140650Y-105210D01*
G01X202000Y-72000D02*
Y-80000D01*
X206000D01*
G01X213800D02*
Y-74667D01*
G01Y-75600D02*
X213400Y-75067D01*
X212800Y-74800D01*
X212100Y-74667D01*
X211400Y-74933D01*
X210800Y-75467D01*
X210400Y-76267D01*
X210200Y-77333D01*
X210400Y-78400D01*
X210800Y-79200D01*
X211400Y-79733D01*
X212100Y-80000D01*
X212800Y-79867D01*
X213400Y-79467D01*
X213800Y-78934D01*
G01X217900Y-82400D02*
X218500Y-82667D01*
X219300Y-82400D01*
X219800Y-81867D01*
X220200Y-81200D01*
X220800Y-79067D01*
X222100Y-74667D01*
G01X218900D02*
X220800Y-79067D01*
G01X226500Y-76400D02*
X229700D01*
X229400Y-75467D01*
X228900Y-74933D01*
X228200Y-74667D01*
X227500Y-74800D01*
X226900Y-75200D01*
X226500Y-76133D01*
X226300Y-76934D01*
Y-77733D01*
X226500Y-78533D01*
X227000Y-79333D01*
X227600Y-79867D01*
X228300Y-80000D01*
X229000Y-79733D01*
X229700Y-78934D01*
G01X234600Y-80000D02*
Y-74667D01*
G01Y-75733D02*
X235100Y-75200D01*
X235600Y-74800D01*
X236300Y-74667D01*
X236800Y-74800D01*
X237400Y-75200D01*
G01X225500Y-122000D02*
Y-130000D01*
G01X223200Y-122000D02*
X227800D01*
G01X233500Y-124667D02*
Y-130000D01*
G01Y-122533D02*
X233300Y-122400D01*
Y-122133D01*
X233500Y-122000D01*
X233700Y-122133D01*
Y-122400D01*
X233500Y-122533D01*
G01X239800Y-130000D02*
Y-124667D01*
G01Y-126000D02*
X240200Y-125333D01*
X240800Y-124800D01*
X241600Y-124667D01*
X242300Y-124800D01*
X242900Y-125333D01*
X243200Y-126267D01*
Y-130000D01*
G01X251300D02*
Y-124667D01*
G01Y-125600D02*
X250900Y-125067D01*
X250300Y-124800D01*
X249600Y-124667D01*
X248900Y-124933D01*
X248300Y-125467D01*
X247900Y-126267D01*
X247700Y-127333D01*
X247900Y-128400D01*
X248300Y-129200D01*
X248900Y-129733D01*
X249600Y-130000D01*
X250300Y-129867D01*
X250900Y-129467D01*
X251300Y-128934D01*
G01X231800Y-97000D02*
X234200D01*
G01X233000D02*
Y-105000D01*
G01X231800D02*
X234200D01*
G01X238700D02*
Y-97000D01*
X243300Y-105000D01*
Y-97000D01*
G01X249000Y-105000D02*
Y-97000D01*
X247800Y-98600D01*
G01Y-105000D02*
X250200D01*
G01X253300Y-78400D02*
X253900Y-79333D01*
X254700Y-79867D01*
X255600Y-80000D01*
X256400Y-79867D01*
X257200Y-79200D01*
X257700Y-78400D01*
X257800Y-77600D01*
X257600Y-76667D01*
X256900Y-76000D01*
X256200Y-75733D01*
X255300D01*
G01X256200D02*
X256800Y-75333D01*
X257300Y-74667D01*
X257500Y-73867D01*
X257300Y-73067D01*
X256800Y-72400D01*
X255900Y-72000D01*
X255000Y-72133D01*
X254100Y-72667D01*
G01X328600Y-123333D02*
X329200Y-122533D01*
X329900Y-122133D01*
X330700Y-122000D01*
X331700Y-122267D01*
X332400Y-122933D01*
X332600Y-123733D01*
X332500Y-124534D01*
X332100Y-125200D01*
X330100Y-126533D01*
X329200Y-127467D01*
X328600Y-128800D01*
X328400Y-130000D01*
X332600D01*
G01X338500Y-122000D02*
X337700Y-122267D01*
X337100Y-122933D01*
X336700Y-123733D01*
X336400Y-124800D01*
X336300Y-126000D01*
X336400Y-127200D01*
X336700Y-128267D01*
X337100Y-129067D01*
X337700Y-129733D01*
X338500Y-130000D01*
X339300Y-129733D01*
X339900Y-129067D01*
X340300Y-128267D01*
X340600Y-127200D01*
X340700Y-126000D01*
X340600Y-124800D01*
X340300Y-123733D01*
X339900Y-122933D01*
X339300Y-122267D01*
X338500Y-122000D01*
G01X346500Y-130000D02*
Y-122000D01*
X345300Y-123600D01*
G01Y-130000D02*
X347700D01*
G01X352300Y-128400D02*
X352900Y-129333D01*
X353700Y-129867D01*
X354600Y-130000D01*
X355400Y-129867D01*
X356200Y-129200D01*
X356700Y-128400D01*
X356800Y-127600D01*
X356600Y-126667D01*
X355900Y-126000D01*
X355200Y-125733D01*
X354300D01*
G01X355200D02*
X355800Y-125333D01*
X356300Y-124667D01*
X356500Y-123867D01*
X356300Y-123067D01*
X355800Y-122400D01*
X354900Y-122000D01*
X354000Y-122133D01*
X353100Y-122667D01*
G01X360700Y-130267D02*
X364300Y-122000D01*
G01X370500D02*
X369700Y-122267D01*
X369100Y-122933D01*
X368700Y-123733D01*
X368400Y-124800D01*
X368300Y-126000D01*
X368400Y-127200D01*
X368700Y-128267D01*
X369100Y-129067D01*
X369700Y-129733D01*
X370500Y-130000D01*
X371300Y-129733D01*
X371900Y-129067D01*
X372300Y-128267D01*
X372600Y-127200D01*
X372700Y-126000D01*
X372600Y-124800D01*
X372300Y-123733D01*
X371900Y-122933D01*
X371300Y-122267D01*
X370500Y-122000D01*
G01X378500Y-130000D02*
Y-122000D01*
X377300Y-123600D01*
G01Y-130000D02*
X379700D01*
G01X384700Y-130267D02*
X388300Y-122000D01*
G01X394500D02*
X393700Y-122267D01*
X393100Y-122933D01*
X392700Y-123733D01*
X392400Y-124800D01*
X392300Y-126000D01*
X392400Y-127200D01*
X392700Y-128267D01*
X393100Y-129067D01*
X393700Y-129733D01*
X394500Y-130000D01*
X395300Y-129733D01*
X395900Y-129067D01*
X396300Y-128267D01*
X396600Y-127200D01*
X396700Y-126000D01*
X396600Y-124800D01*
X396300Y-123733D01*
X395900Y-122933D01*
X395300Y-122267D01*
X394500Y-122000D01*
G01X400800Y-129067D02*
X401500Y-129733D01*
X402300Y-130000D01*
X403100Y-129733D01*
X403800Y-128934D01*
X404300Y-127733D01*
X404500Y-126533D01*
Y-125067D01*
X404300Y-123867D01*
X403800Y-122800D01*
X403200Y-122267D01*
X402500Y-122000D01*
X401700Y-122267D01*
X401100Y-122800D01*
X400700Y-123600D01*
X400500Y-124667D01*
X400700Y-125600D01*
X401200Y-126533D01*
X401800Y-127067D01*
X402500Y-127200D01*
X403300Y-126934D01*
X403900Y-126267D01*
X404500Y-125067D01*
G01X328300Y-105000D02*
Y-97000D01*
X330300D01*
X331100Y-97400D01*
X331700Y-97933D01*
X332200Y-98733D01*
X332600Y-99667D01*
X332700Y-101000D01*
X332600Y-102333D01*
X332200Y-103267D01*
X331700Y-104067D01*
X331100Y-104600D01*
X330300Y-105000D01*
X328300D01*
G01X336000D02*
X338500Y-97000D01*
X341000Y-105000D01*
G01X340100Y-102200D02*
X336900D01*
G01X346500Y-97000D02*
Y-105000D01*
G01X344200Y-97000D02*
X348800D01*
G01X352600Y-101667D02*
X353300Y-100733D01*
X353900Y-100200D01*
X354700Y-99933D01*
X355400Y-100200D01*
X355900Y-100733D01*
X356300Y-101533D01*
X356400Y-102467D01*
X356300Y-103267D01*
X355900Y-104067D01*
X355300Y-104733D01*
X354600Y-105000D01*
X353800Y-104733D01*
X353100Y-103934D01*
X352700Y-102733D01*
X352600Y-101400D01*
X352800Y-99667D01*
X353100Y-98733D01*
X353600Y-97800D01*
X354300Y-97133D01*
X355000Y-97000D01*
X355700Y-97267D01*
X356200Y-97933D01*
G01X359900Y-105000D02*
Y-97000D01*
X362500Y-103667D01*
X365100Y-97000D01*
Y-105000D01*
G01X370500Y-97000D02*
Y-105000D01*
G01X368200Y-97000D02*
X372800D01*
G01X379300Y-100733D02*
X379700Y-100333D01*
X380000Y-99667D01*
X380200Y-98733D01*
X380000Y-97933D01*
X379600Y-97400D01*
X378900Y-97000D01*
X376200D01*
Y-105000D01*
X379500D01*
X380200Y-104467D01*
X380600Y-103667D01*
X380800Y-102733D01*
X380600Y-101800D01*
X380000Y-101000D01*
X379300Y-100733D01*
X376200D01*
G01X386500Y-105000D02*
X387200Y-104867D01*
X388000Y-104467D01*
X388500Y-103800D01*
X388700Y-102867D01*
X388500Y-101934D01*
X387900Y-101133D01*
X387000Y-100733D01*
X386000D01*
X385400Y-100467D01*
X384900Y-99800D01*
X384700Y-98867D01*
X385000Y-97933D01*
X385700Y-97267D01*
X386500Y-97000D01*
X387300Y-97267D01*
X388000Y-97933D01*
X388300Y-98867D01*
X388100Y-99800D01*
X387600Y-100467D01*
X387000Y-100733D01*
X386000D01*
X385100Y-101133D01*
X384500Y-101934D01*
X384300Y-102867D01*
X384500Y-103800D01*
X385000Y-104467D01*
X385800Y-104867D01*
X386500Y-105000D01*
G01X394500D02*
X395200Y-104867D01*
X396000Y-104467D01*
X396500Y-103800D01*
X396700Y-102867D01*
X396500Y-101934D01*
X395900Y-101133D01*
X395000Y-100733D01*
X394000D01*
X393400Y-100467D01*
X392900Y-99800D01*
X392700Y-98867D01*
X393000Y-97933D01*
X393700Y-97267D01*
X394500Y-97000D01*
X395300Y-97267D01*
X396000Y-97933D01*
X396300Y-98867D01*
X396100Y-99800D01*
X395600Y-100467D01*
X395000Y-100733D01*
X394000D01*
X393100Y-101133D01*
X392500Y-101934D01*
X392300Y-102867D01*
X392500Y-103800D01*
X393000Y-104467D01*
X393800Y-104867D01*
X394500Y-105000D01*
G01X400000D02*
X402500Y-97000D01*
X405000Y-105000D01*
G01X404100Y-102200D02*
X400900D01*
G01X410500Y-97000D02*
X409700Y-97267D01*
X409100Y-97933D01*
X408700Y-98733D01*
X408400Y-99800D01*
X408300Y-101000D01*
X408400Y-102200D01*
X408700Y-103267D01*
X409100Y-104067D01*
X409700Y-104733D01*
X410500Y-105000D01*
X411300Y-104733D01*
X411900Y-104067D01*
X412300Y-103267D01*
X412600Y-102200D01*
X412700Y-101000D01*
X412600Y-99800D01*
X412300Y-98733D01*
X411900Y-97933D01*
X411300Y-97267D01*
X410500Y-97000D01*
G01X350500Y-72000D02*
Y-80000D01*
G01X348200Y-72000D02*
X352800D01*
G01X356600Y-76667D02*
X357300Y-75733D01*
X357900Y-75200D01*
X358700Y-74933D01*
X359400Y-75200D01*
X359900Y-75733D01*
X360300Y-76533D01*
X360400Y-77467D01*
X360300Y-78267D01*
X359900Y-79067D01*
X359300Y-79733D01*
X358600Y-80000D01*
X357800Y-79733D01*
X357100Y-78934D01*
X356700Y-77733D01*
X356600Y-76400D01*
X356800Y-74667D01*
X357100Y-73733D01*
X357600Y-72800D01*
X358300Y-72133D01*
X359000Y-72000D01*
X359700Y-72267D01*
X360200Y-72933D01*
G01X363900Y-80000D02*
Y-72000D01*
X366500Y-78667D01*
X369100Y-72000D01*
Y-80000D01*
G01X375100Y-76000D02*
X377100D01*
Y-78400D01*
X376500Y-79200D01*
X375800Y-79733D01*
X374800Y-80000D01*
X373800Y-79733D01*
X373100Y-79200D01*
X372500Y-78400D01*
X372100Y-77467D01*
X371900Y-76400D01*
Y-75467D01*
X372100Y-74667D01*
X372500Y-73733D01*
X373100Y-72933D01*
X373700Y-72400D01*
X374500Y-72000D01*
X375200D01*
X376000Y-72267D01*
X376600Y-72800D01*
G01X379500Y-82667D02*
X385500D01*
G01X388500Y-80000D02*
Y-72000D01*
X390900D01*
X391700Y-72400D01*
X392300Y-73333D01*
X392500Y-74400D01*
X392300Y-75467D01*
X391800Y-76267D01*
X390900Y-76667D01*
X388500D01*
G01X396300Y-80000D02*
Y-72000D01*
X398300D01*
X399100Y-72400D01*
X399700Y-72933D01*
X400200Y-73733D01*
X400600Y-74667D01*
X400700Y-76000D01*
X400600Y-77333D01*
X400200Y-78267D01*
X399700Y-79067D01*
X399100Y-79600D01*
X398300Y-80000D01*
X396300D01*
G01X407300Y-75733D02*
X407700Y-75333D01*
X408000Y-74667D01*
X408200Y-73733D01*
X408000Y-72933D01*
X407600Y-72400D01*
X406900Y-72000D01*
X404200D01*
Y-80000D01*
X407500D01*
X408200Y-79467D01*
X408600Y-78667D01*
X408800Y-77733D01*
X408600Y-76800D01*
X408000Y-76000D01*
X407300Y-75733D01*
X404200D01*
G01X411500Y-82667D02*
X417500D01*
G01X420000Y-80000D02*
X422500Y-72000D01*
X425000Y-80000D01*
G01X424100Y-77200D02*
X420900D01*
G01X427500Y-82667D02*
X433500D01*
G01X439300Y-75733D02*
X439700Y-75333D01*
X440000Y-74667D01*
X440200Y-73733D01*
X440000Y-72933D01*
X439600Y-72400D01*
X438900Y-72000D01*
X436200D01*
Y-80000D01*
X439500D01*
X440200Y-79467D01*
X440600Y-78667D01*
X440800Y-77733D01*
X440600Y-76800D01*
X440000Y-76000D01*
X439300Y-75733D01*
X436200D01*
G01X444300Y-80000D02*
Y-72000D01*
X446300D01*
X447100Y-72400D01*
X447700Y-72933D01*
X448200Y-73733D01*
X448600Y-74667D01*
X448700Y-76000D01*
X448600Y-77333D01*
X448200Y-78267D01*
X447700Y-79067D01*
X447100Y-79600D01*
X446300Y-80000D01*
X444300D01*
G01X443000Y-130000D02*
X445500Y-122000D01*
X448000Y-130000D01*
G01X447100Y-127200D02*
X443900D01*
G01X473000Y-130000D02*
Y-122000D01*
X471800Y-123600D01*
G01Y-130000D02*
X474200D01*
G01X479100Y-126667D02*
X479800Y-125733D01*
X480400Y-125200D01*
X481200Y-124933D01*
X481900Y-125200D01*
X482400Y-125733D01*
X482800Y-126533D01*
X482900Y-127467D01*
X482800Y-128267D01*
X482400Y-129067D01*
X481800Y-129733D01*
X481100Y-130000D01*
X480300Y-129733D01*
X479600Y-128934D01*
X479200Y-127733D01*
X479100Y-126400D01*
X479300Y-124667D01*
X479600Y-123733D01*
X480100Y-122800D01*
X480800Y-122133D01*
X481500Y-122000D01*
X482200Y-122267D01*
X482700Y-122933D01*
G54D11*
X22480Y328649D03*
G54D12*
X25389Y707364D03*
X7673Y703427D03*
X15547Y715238D03*
X25389D03*
X7673Y711301D03*
X15547Y770357D03*
Y778231D03*
X7673Y774293D03*
Y782167D03*
X15547Y786105D03*
X7673Y790041D03*
X15547Y849097D03*
X25389D03*
X7673Y845160D03*
X25389Y864845D03*
X15547Y896341D03*
X25389Y880593D03*
Y888467D03*
X7673Y900278D03*
X15547Y912089D03*
Y919963D03*
X25389D03*
Y927837D03*
Y935711D03*
X15547Y959333D03*
X25389Y975081D03*
X7673Y955396D03*
Y971144D03*
Y979018D03*
X25389Y990829D03*
Y998703D03*
X15551Y1065629D03*
X7677Y1061692D03*
X25393Y1081377D03*
Y1089251D03*
X7677Y1077440D03*
Y1085314D03*
X15551Y1120748D03*
X25393Y1097125D03*
X15551Y1136496D03*
Y1144370D03*
X25393Y1136496D03*
Y1144370D03*
X7677Y1124684D03*
X25393Y1160118D03*
X15551Y1183740D03*
X7677Y1179803D03*
X25393Y1199488D03*
Y1207362D03*
Y1215236D03*
X7677Y1195551D03*
Y1203425D03*
X15551Y1238858D03*
X25393Y1223110D03*
X15551Y1254606D03*
Y1262480D03*
X7677Y1242795D03*
X15551Y1270354D03*
Y1286102D03*
Y1301850D03*
X25393Y1293976D03*
X7677Y1297913D03*
X15551Y1333346D03*
X25393Y1325472D03*
X7677Y1321535D03*
Y1353031D03*
X15551Y1349094D03*
X33263Y703427D03*
Y711301D03*
Y719175D03*
Y845160D03*
Y868782D03*
Y876656D03*
Y884530D03*
Y916026D03*
Y923900D03*
Y939648D03*
Y979018D03*
Y994766D03*
Y1002640D03*
X33267Y1077440D03*
Y1085314D03*
Y1101062D03*
Y1140432D03*
Y1148306D03*
Y1156180D03*
Y1195551D03*
Y1203425D03*
Y1219173D03*
Y1227047D03*
Y1290039D03*
Y1305787D03*
Y1313661D03*
Y1337283D03*
G54D13*
X45056Y1685410D03*
Y1701945D03*
Y1718480D03*
Y1735016D03*
Y1751551D03*
Y1784622D03*
Y1801158D03*
G54D14*
X64979Y35500D03*
Y45500D03*
X54979Y40500D03*
X64979Y65500D03*
X54979Y60500D03*
Y70500D03*
X203542Y73105D03*
X204069Y152050D03*
X204137Y247568D03*
X204597Y331786D03*
X203541Y421732D03*
X204333Y506517D03*
X206668Y598130D03*
X204596Y681645D03*
X205626Y774526D03*
X205386Y856244D03*
X210091Y947202D03*
X205030Y1122856D03*
X205122Y1206233D03*
X205626Y1299104D03*
X204332Y1380966D03*
X203243Y1474162D03*
X204859Y1557277D03*
X205923Y1648177D03*
X205387Y1731351D03*
X205310Y1823227D03*
X204069Y1900420D03*
X205905Y1998730D03*
X205310Y2043388D03*
G54D15*
X119920Y68071D03*
Y218071D03*
Y228071D03*
Y238071D03*
Y248071D03*
Y258071D03*
Y268071D03*
Y278071D03*
Y288071D03*
Y298071D03*
Y308071D03*
Y318071D03*
Y328071D03*
Y366102D03*
Y566102D03*
Y576102D03*
Y586102D03*
Y596102D03*
Y606102D03*
Y616102D03*
Y626102D03*
Y636102D03*
Y646102D03*
Y656102D03*
Y666102D03*
Y676102D03*
Y914134D03*
Y924134D03*
Y934134D03*
Y944134D03*
Y954134D03*
Y964134D03*
Y974134D03*
Y984134D03*
Y994134D03*
Y1004134D03*
Y1014134D03*
Y1024134D03*
Y1262165D03*
Y1272165D03*
Y1282165D03*
Y1292165D03*
Y1302165D03*
Y1312165D03*
Y1322165D03*
Y1332165D03*
Y1342165D03*
Y1352165D03*
Y1362165D03*
Y1372165D03*
Y1610197D03*
Y1620197D03*
Y1630197D03*
Y1640197D03*
Y1650197D03*
Y1660197D03*
Y1670197D03*
Y1680197D03*
Y1690197D03*
Y1700197D03*
Y1710197D03*
Y1720197D03*
Y1958228D03*
Y1968228D03*
Y1978228D03*
Y1988228D03*
Y1998228D03*
Y2008228D03*
Y2018228D03*
Y2028228D03*
Y2038228D03*
Y2048228D03*
Y2058228D03*
Y2068228D03*
X139920Y58071D03*
Y228071D03*
Y218071D03*
Y248071D03*
Y238071D03*
Y268071D03*
Y258071D03*
Y298071D03*
Y288071D03*
Y278071D03*
Y318071D03*
Y308071D03*
Y328071D03*
Y566102D03*
Y586102D03*
Y576102D03*
Y606102D03*
Y596102D03*
Y636102D03*
Y626102D03*
Y616102D03*
Y656102D03*
Y646102D03*
Y676102D03*
Y666102D03*
Y924134D03*
Y914134D03*
Y944134D03*
Y934134D03*
Y974134D03*
Y964134D03*
Y954134D03*
Y994134D03*
Y984134D03*
Y1024134D03*
Y1014134D03*
Y1004134D03*
Y1262165D03*
Y1282165D03*
Y1272165D03*
Y1312165D03*
Y1302165D03*
Y1292165D03*
Y1332165D03*
Y1322165D03*
Y1362165D03*
Y1352165D03*
Y1342165D03*
Y1372165D03*
Y1620197D03*
Y1610197D03*
Y1650197D03*
Y1640197D03*
Y1630197D03*
Y1670197D03*
Y1660197D03*
Y1700197D03*
Y1690197D03*
Y1680197D03*
Y1720197D03*
Y1710197D03*
Y1958228D03*
Y1988228D03*
Y1978228D03*
Y1968228D03*
Y2008228D03*
Y1998228D03*
Y2038228D03*
Y2028228D03*
Y2018228D03*
Y2058228D03*
Y2048228D03*
Y2068228D03*
G54D16*
X253385Y21890D03*
Y32520D03*
X263385Y21890D03*
Y32520D03*
X253385Y196890D03*
X263385D03*
X253385Y207520D03*
X263385D03*
X253385Y371890D03*
X263385D03*
X253385Y382520D03*
X263385D03*
X253386Y546890D03*
Y557520D03*
X263386Y546890D03*
Y557520D03*
X253386Y721890D03*
Y732520D03*
X263386Y721890D03*
Y732520D03*
X253385Y896890D03*
X263385D03*
X253385Y907520D03*
X263385D03*
X253385Y1071890D03*
X263385D03*
X253385Y1082520D03*
X263385D03*
X253385Y1246890D03*
Y1257520D03*
X263385Y1246890D03*
Y1257520D03*
X253385Y1421890D03*
Y1432520D03*
X263385Y1421890D03*
Y1432520D03*
X253385Y1596890D03*
X263385D03*
X253385Y1607520D03*
X263385D03*
X253385Y1771890D03*
X263385D03*
X253385Y1782520D03*
X263385D03*
X253385Y1946890D03*
Y1957520D03*
X263385Y1946890D03*
Y1957520D03*
X273385Y21890D03*
Y32520D03*
X283385Y21890D03*
Y32520D03*
X273385Y196890D03*
X283385D03*
X273385Y207520D03*
X283385D03*
X273385Y371890D03*
X283385D03*
X273385Y382520D03*
X283385D03*
X273386Y546890D03*
Y557520D03*
X283386Y546890D03*
Y557520D03*
X273386Y721890D03*
Y732520D03*
X283386Y721890D03*
Y732520D03*
X273385Y896890D03*
X283385D03*
X273385Y907520D03*
X283385D03*
X273385Y1071890D03*
X283385D03*
X273385Y1082520D03*
X283385D03*
X273385Y1246890D03*
Y1257520D03*
X283385Y1246890D03*
Y1257520D03*
X273385Y1421890D03*
Y1432520D03*
X283385Y1421890D03*
Y1432520D03*
X273385Y1596890D03*
X283385D03*
X273385Y1607520D03*
X283385D03*
X273385Y1771890D03*
X283385D03*
X273385Y1782520D03*
X283385D03*
X273385Y1946890D03*
Y1957520D03*
X283385Y1946890D03*
Y1957520D03*
X293385Y21890D03*
Y32520D03*
X303385Y21890D03*
Y32520D03*
X313385D03*
Y21890D03*
X293385Y196890D03*
X303385D03*
X313385D03*
X293385Y207520D03*
X303385D03*
X313385D03*
X293385Y371890D03*
X303385D03*
X313385D03*
X293385Y382520D03*
X303385D03*
X313385D03*
X293386Y546890D03*
Y557520D03*
X303386Y546890D03*
Y557520D03*
X313386D03*
Y546890D03*
X293386Y721890D03*
Y732520D03*
X303386Y721890D03*
Y732520D03*
X313386D03*
Y721890D03*
X293385Y896890D03*
X303385D03*
X313385D03*
X293385Y907520D03*
X303385D03*
X313385D03*
X293385Y1071890D03*
X303385D03*
X313385D03*
X293385Y1082520D03*
X303385D03*
X313385D03*
X293385Y1246890D03*
Y1257520D03*
X303385Y1246890D03*
Y1257520D03*
X313385D03*
Y1246890D03*
X293385Y1421890D03*
Y1432520D03*
X303385Y1421890D03*
Y1432520D03*
X313385D03*
Y1421890D03*
X293385Y1596890D03*
X303385D03*
X313385D03*
X293385Y1607520D03*
X303385D03*
X313385D03*
X293385Y1771890D03*
X303385D03*
X313385D03*
X293385Y1782520D03*
X303385D03*
X313385D03*
X293385Y1946890D03*
Y1957520D03*
X303385Y1946890D03*
Y1957520D03*
X313385D03*
Y1946890D03*
X337165Y24705D03*
X323385Y32520D03*
Y21890D03*
Y196890D03*
X337165Y209705D03*
X323385Y207520D03*
Y371890D03*
X337165Y374705D03*
X323385Y382520D03*
X337166Y559705D03*
X323386Y557520D03*
Y546890D03*
X337166Y724705D03*
X323386Y732520D03*
Y721890D03*
X323385Y896890D03*
X337165Y909705D03*
X323385Y907520D03*
Y1071890D03*
X337165Y1074705D03*
X323385Y1082520D03*
X337165Y1259705D03*
X323385Y1257520D03*
Y1246890D03*
X337165Y1424705D03*
X323385Y1432520D03*
Y1421890D03*
Y1596890D03*
X337165Y1609705D03*
X323385Y1607520D03*
Y1771890D03*
X337165Y1774705D03*
Y1784705D03*
X323385Y1782520D03*
X337165Y1959705D03*
X323385Y1957520D03*
Y1946890D03*
X342165Y19705D03*
X357165Y24705D03*
X362165Y19705D03*
Y29705D03*
X357165Y34705D03*
X347165Y199705D03*
X342165Y204705D03*
X347165Y209705D03*
X342165Y369705D03*
X362165D03*
X357165Y374705D03*
Y384705D03*
X362165Y379705D03*
X342166Y554705D03*
X347166Y549705D03*
Y559705D03*
X342166Y719705D03*
X357166Y724705D03*
X362166Y719705D03*
Y729705D03*
X357166Y734705D03*
X347165Y899705D03*
X342165Y904705D03*
X347165Y909705D03*
X342165Y1069705D03*
X362165D03*
X357165Y1074705D03*
Y1084705D03*
X362165Y1079705D03*
X342165Y1254705D03*
X347165Y1249705D03*
Y1259705D03*
X342165Y1419705D03*
X357165Y1424705D03*
Y1434705D03*
X362165Y1419705D03*
Y1429705D03*
X347165Y1599705D03*
X342165Y1604705D03*
X347165Y1609705D03*
X342165Y1769705D03*
X362165D03*
X342165Y1779705D03*
X357165Y1774705D03*
Y1784705D03*
X362165Y1779705D03*
X342165Y1954705D03*
X347165Y1949705D03*
Y1959705D03*
G54D17*
G01X203542Y69353D02*
Y73105D01*
G01D02*
Y76857D01*
G01X199790Y73105D02*
X203542D01*
G01D02*
X207294D01*
G01X204069Y148298D02*
Y152050D01*
G01D02*
Y155802D01*
G01X200317Y152050D02*
X204069D01*
G01D02*
X207821D01*
G01X204137Y243816D02*
Y247568D01*
G01D02*
Y251320D01*
G01X200385Y247568D02*
X204137D01*
G01D02*
X207889D01*
G01X204597Y328034D02*
Y331786D01*
G01D02*
Y335538D01*
G01X200845Y331786D02*
X204597D01*
G01D02*
X208349D01*
G01X203541Y417980D02*
Y421732D01*
G01D02*
Y425484D01*
G01X199789Y421732D02*
X203541D01*
G01D02*
X207293D01*
G01X204333Y502765D02*
Y506517D01*
G01D02*
Y510269D01*
G01X200581Y506517D02*
X204333D01*
G01D02*
X208085D01*
G01X206668Y594378D02*
Y598130D01*
G01D02*
Y601882D01*
G01X202916Y598130D02*
X206668D01*
G01D02*
X210420D01*
G01X204596Y677893D02*
Y681645D01*
G01D02*
Y685397D01*
G01X200844Y681645D02*
X204596D01*
G01D02*
X208348D01*
G01X205626Y770774D02*
Y774526D01*
G01D02*
Y778278D01*
G01X201874Y774526D02*
X205626D01*
G01D02*
X209378D01*
G01X205386Y852492D02*
Y856244D01*
G01D02*
Y859996D01*
G01X201634Y856244D02*
X205386D01*
G01D02*
X209138D01*
G01X210091Y943450D02*
Y947202D01*
G01D02*
Y950954D01*
G01X206339Y947202D02*
X210091D01*
G01D02*
X213843D01*
G01X205030Y1119104D02*
Y1122856D01*
G01D02*
Y1126608D01*
G01X201278Y1122856D02*
X205030D01*
G01D02*
X208782D01*
G01X205122Y1202481D02*
Y1206233D01*
G01D02*
Y1209985D01*
G01X201370Y1206233D02*
X205122D01*
G01D02*
X208874D01*
G01X205626Y1295352D02*
Y1299104D01*
G01D02*
Y1302856D01*
G01X201874Y1299104D02*
X205626D01*
G01D02*
X209378D01*
G01X204332Y1377214D02*
Y1380966D01*
G01D02*
Y1384718D01*
G01X200580Y1380966D02*
X204332D01*
G01D02*
X208084D01*
G01X203243Y1470410D02*
Y1474162D01*
G01D02*
Y1477914D01*
G01X199491Y1474162D02*
X203243D01*
G01D02*
X206995D01*
G01X204859Y1553525D02*
Y1557277D01*
G01D02*
Y1561029D01*
G01X201107Y1557277D02*
X204859D01*
G01D02*
X208611D01*
G01X205923Y1644425D02*
Y1648177D01*
G01D02*
Y1651929D01*
G01X202171Y1648177D02*
X205923D01*
G01D02*
X209675D01*
G01X205387Y1727599D02*
Y1731351D01*
G01D02*
Y1735103D01*
G01X201635Y1731351D02*
X205387D01*
G01D02*
X209139D01*
G01X205310Y1819475D02*
Y1823227D01*
G01D02*
Y1826979D01*
G01X201558Y1823227D02*
X205310D01*
G01D02*
X209062D01*
G01X204069Y1896668D02*
Y1900420D01*
G01D02*
Y1904172D01*
G01X200317Y1900420D02*
X204069D01*
G01D02*
X207821D01*
G01X205905Y1994978D02*
Y1998730D01*
G01D02*
Y2002482D01*
G01X202153Y1998730D02*
X205905D01*
G01D02*
X209657D01*
G01X205310Y2039636D02*
Y2043388D01*
G01D02*
Y2047140D01*
G01X201558Y2043388D02*
X205310D01*
G01D02*
X209062D01*
G54D18*
G01X312527Y1162266D02*
X309684Y1165109D01*
X237865D01*
X202218Y1129462D01*
X163230D01*
X158941Y1125173D01*
X150166D01*
X148374Y1126965D01*
X136018D01*
X126035Y1116982D01*
X113625D01*
X112503Y1115860D01*
G01X158456Y1129045D02*
X163048Y1133637D01*
X200917D01*
X236261Y1168981D01*
X308875D01*
X312698Y1172804D01*
G54D19*
G01X15547Y770357D02*
X11972Y766782D01*
Y761408D01*
X13936Y759444D01*
X17756D01*
X21043Y756157D01*
Y754209D01*
X23909Y751343D01*
X27883D01*
X31475Y747751D01*
X35619D01*
X39678Y743692D01*
Y701414D01*
X77271Y663821D01*
Y519469D01*
X35141Y477339D01*
Y451998D01*
X48524Y438615D01*
Y422178D01*
X43704Y417358D01*
Y358997D01*
X56002Y346699D01*
Y299139D01*
X43876Y287013D01*
Y241030D01*
X72394Y212512D01*
Y164931D01*
X37359Y129896D01*
Y84879D01*
X45492Y76746D01*
Y60865D01*
X51543Y54814D01*
X56224D01*
X60393Y50645D01*
Y40086D01*
X64979Y35500D01*
G01X54979Y40500D02*
Y44138D01*
X44192Y54925D01*
Y76207D01*
X36059Y84340D01*
Y130436D01*
X71094Y165471D01*
Y211973D01*
X42576Y240491D01*
Y287552D01*
X54702Y299678D01*
Y346160D01*
X42404Y358458D01*
Y417897D01*
X47224Y422717D01*
Y438076D01*
X33841Y451459D01*
Y477878D01*
X75971Y520008D01*
Y663282D01*
X38281Y700972D01*
Y743199D01*
X35296Y746184D01*
X30825D01*
X27233Y749776D01*
X23259D01*
X19476Y753559D01*
Y755507D01*
X17106Y757877D01*
X13286D01*
X10736Y760428D01*
Y760429D01*
X10672Y760493D01*
Y771294D01*
X7673Y774293D01*
G01X64979Y45500D02*
X69828Y50349D01*
Y58471D01*
X67853Y60446D01*
X61856D01*
X58016Y56606D01*
X51798D01*
X46792Y61612D01*
Y77285D01*
X38659Y85418D01*
Y129357D01*
X73694Y164392D01*
Y213051D01*
X45176Y241569D01*
Y286474D01*
X57302Y298600D01*
Y347238D01*
X45004Y359536D01*
Y416819D01*
X49824Y421639D01*
Y439154D01*
X36441Y452537D01*
Y476800D01*
X78571Y518930D01*
Y664360D01*
X40978Y701953D01*
Y747838D01*
X34417Y754399D01*
X30611D01*
X27363Y757647D01*
X23580D01*
X18360Y762867D01*
Y775418D01*
X15547Y778231D01*
G01X64979Y65500D02*
X53437D01*
X49392Y69545D01*
Y78363D01*
X41259Y86496D01*
Y128279D01*
X76294Y163314D01*
Y214130D01*
X47776Y242648D01*
Y285396D01*
X59902Y297522D01*
Y348316D01*
X47604Y360614D01*
Y415741D01*
X52424Y420561D01*
Y440233D01*
X39041Y453616D01*
Y475722D01*
X81171Y517852D01*
Y665438D01*
X43578Y703031D01*
Y753410D01*
X35120Y761868D01*
X31585D01*
X27591Y765862D01*
X22970D01*
X20960Y767872D01*
Y783024D01*
X17879Y786105D01*
X15547D01*
G01X7673Y790041D02*
X17099D01*
X22260Y784880D01*
Y768411D01*
X23509Y767162D01*
X28130D01*
X32124Y763168D01*
X35659D01*
X44878Y753949D01*
Y703570D01*
X82471Y665977D01*
Y517313D01*
X40341Y475183D01*
Y454155D01*
X53724Y440772D01*
Y419995D01*
X48923Y415194D01*
Y361161D01*
X61221Y348863D01*
Y296975D01*
X49076Y284830D01*
Y243187D01*
X77594Y214669D01*
Y162775D01*
X42559Y127740D01*
Y87035D01*
X50692Y78902D01*
Y74787D01*
X54979Y70500D01*
G01X7673Y782167D02*
X17539D01*
X19660Y780046D01*
Y763406D01*
X24119Y758947D01*
X27902D01*
X31150Y755699D01*
X34957D01*
X42278Y748378D01*
Y702492D01*
X79871Y664899D01*
Y518391D01*
X37741Y476261D01*
Y453076D01*
X51124Y439693D01*
Y421100D01*
X46304Y416280D01*
Y360075D01*
X58602Y347777D01*
Y298061D01*
X46476Y285935D01*
Y242109D01*
X74994Y213591D01*
Y163853D01*
X39959Y128818D01*
Y85957D01*
X48092Y77824D01*
Y67387D01*
X54979Y60500D01*
G01X119920Y68071D02*
X114503Y73488D01*
Y82794D01*
X94848Y102449D01*
Y350137D01*
X86015Y358970D01*
Y415704D01*
X89827Y419516D01*
Y660461D01*
X55040Y695248D01*
Y774249D01*
X44131Y785158D01*
X30665D01*
X26789Y789034D01*
X23654D01*
X20118Y792570D01*
Y844526D01*
X15547Y849097D01*
G01X7673Y845160D02*
X14391Y851878D01*
X16723D01*
X22357Y846244D01*
Y792585D01*
X24143Y790799D01*
X28234D01*
X31872Y787161D01*
X45364D01*
X56363Y776162D01*
Y695764D01*
X91173Y660954D01*
Y419786D01*
X93223Y417736D01*
G01X7673Y900278D02*
X13561D01*
X13971Y900688D01*
X27573D01*
X31087Y897174D01*
X38990D01*
X53026Y883138D01*
Y874597D01*
X86416Y841207D01*
Y794520D01*
X71742Y779846D01*
Y712783D01*
X107310Y677215D01*
Y667983D01*
X105071Y665744D01*
Y431951D01*
X107640Y429382D01*
Y423353D01*
X106004Y421717D01*
Y410662D01*
X102981Y407639D01*
Y399996D01*
X101348Y398363D01*
Y367396D01*
X117031Y351713D01*
X210046D01*
X308057Y253702D01*
Y248863D01*
G01X15547Y896341D02*
X18411Y899205D01*
X26958D01*
X30472Y895691D01*
X37952D01*
X44229Y889414D01*
Y805301D01*
X70420Y779110D01*
Y712265D01*
X106010Y676675D01*
Y668522D01*
X103630Y666142D01*
Y431325D01*
X106340Y428615D01*
Y423892D01*
X104392Y421944D01*
Y410890D01*
X101681Y408179D01*
Y400844D01*
X100029Y399192D01*
Y366810D01*
X116473Y350366D01*
X208952D01*
X304925Y254393D01*
Y242352D01*
X306267Y241010D01*
G01X314940Y252084D02*
X212527Y354497D01*
X118678D01*
X104365Y368810D01*
Y396117D01*
X108604Y400356D01*
Y420639D01*
X110719Y422754D01*
Y430884D01*
X106371Y435232D01*
Y665205D01*
X109164Y667998D01*
Y688147D01*
X74387Y722924D01*
Y778308D01*
X89412Y793333D01*
Y862950D01*
X47097Y905265D01*
X31179D01*
X27652Y908792D01*
X14541D01*
X12728Y910605D01*
Y917144D01*
X15547Y919963D01*
G01X320961Y250105D02*
X215177Y355889D01*
X121309D01*
X112767Y364431D01*
Y392933D01*
X110185Y395515D01*
Y415068D01*
X112767Y417650D01*
Y437504D01*
X112765Y437506D01*
Y686385D01*
X75797Y723353D01*
Y777485D01*
X90849Y792537D01*
Y864770D01*
X44347Y911272D01*
X31886D01*
X28099Y915059D01*
X18517D01*
X15547Y912089D01*
G01X319305Y582111D02*
X315890Y585526D01*
Y619718D01*
X234097Y701511D01*
X122995D01*
X100626Y723880D01*
Y764849D01*
X104936Y769159D01*
Y891513D01*
X36250Y960199D01*
X31372D01*
X27306Y956133D01*
X13475D01*
X11278Y958330D01*
Y967539D01*
X7673Y971144D01*
G01X317724Y588250D02*
Y619809D01*
X234661Y702872D01*
X123509D01*
X102058Y724323D01*
Y764080D01*
X106337Y768359D01*
Y896229D01*
X36545Y966021D01*
X31798D01*
X28206Y962429D01*
X18643D01*
X15547Y959333D01*
G01X321742Y599041D02*
Y617770D01*
X233809Y705703D01*
X122690D01*
X108937Y719456D01*
Y895798D01*
X38137Y966598D01*
Y972320D01*
X36359Y974098D01*
X31365D01*
X27327Y970060D01*
X16631D01*
X7673Y979018D01*
G01Y955396D02*
X11265D01*
X12335Y954326D01*
X27601D01*
X31988Y958713D01*
X35566D01*
X103589Y890690D01*
Y769863D01*
X90876Y757150D01*
Y731657D01*
X122377Y700156D01*
X233535D01*
X313511Y620180D01*
Y583360D01*
X320380Y576491D01*
G01X321425Y951577D02*
Y967665D01*
X251123Y1037967D01*
X69001D01*
X49698Y1057270D01*
X29613D01*
X25486Y1061397D01*
X22588D01*
X22293Y1061692D01*
X7677D01*
G01X324098Y946104D02*
Y966831D01*
X251565Y1039364D01*
X69580D01*
X50374Y1058570D01*
X30152D01*
X26025Y1062697D01*
X24268D01*
X21336Y1065629D01*
X15551D01*
G01X326646Y939788D02*
Y966123D01*
X251833Y1040936D01*
X70844D01*
X47011Y1064769D01*
X30717D01*
X26713Y1068773D01*
X13723D01*
X10437Y1072059D01*
Y1074680D01*
X7677Y1077440D01*
G01Y1085314D02*
X12041Y1080950D01*
Y1072618D01*
X14357Y1070302D01*
X27347D01*
X31351Y1066298D01*
X47321D01*
X71383Y1042236D01*
X252382D01*
X328583Y966035D01*
Y953727D01*
X331721Y950589D01*
Y947325D01*
X328583Y944187D01*
Y933262D01*
G01X327452Y1279447D02*
X235836Y1371063D01*
X184050D01*
X175521Y1379592D01*
X118235D01*
X111227Y1372584D01*
Y1152530D01*
X82114Y1123417D01*
X38223D01*
X36269Y1121463D01*
X30991D01*
X27476Y1117948D01*
X22700D01*
X15964Y1124684D01*
X7677D01*
G01X321978Y1282086D02*
X234301Y1369763D01*
X183511D01*
X175389Y1377885D01*
X118943D01*
X112576Y1371518D01*
Y1151971D01*
X82673Y1122068D01*
X38956D01*
X36982Y1120094D01*
X32488D01*
X28623Y1116229D01*
X20070D01*
X15551Y1120748D01*
G01X327932Y1289221D02*
X321357D01*
X236671Y1373907D01*
X186724D01*
X176562Y1384069D01*
X116185D01*
X107274Y1375158D01*
Y1154169D01*
X85133Y1132028D01*
X41222D01*
X37682Y1135568D01*
X31866D01*
X28537Y1132239D01*
X23801D01*
X19544Y1136496D01*
X15551D01*
G01Y1144370D02*
X11695Y1140514D01*
Y1135100D01*
X13057Y1133738D01*
X16309D01*
X24477Y1125570D01*
X27916D01*
X31565Y1129219D01*
X34296D01*
X35206Y1130129D01*
X85073D01*
X108574Y1153630D01*
Y1374619D01*
X116724Y1382769D01*
X176023D01*
X186429Y1372363D01*
X236375D01*
X324722Y1284016D01*
X329619D01*
G01X323720Y1570924D02*
X328721Y1565923D01*
Y1418538D01*
X323989Y1413806D01*
X166233D01*
X153871Y1401444D01*
X100086D01*
X85201Y1386559D01*
Y1222083D01*
X47741Y1184623D01*
X31645D01*
X27986Y1188282D01*
X22884D01*
X19497Y1191669D01*
Y1193054D01*
X17000Y1195551D01*
X7677D01*
G01X333474Y1566686D02*
X331321Y1564533D01*
Y1417460D01*
X325067Y1411206D01*
X167311D01*
X153472Y1397367D01*
X108942D01*
X89519Y1377944D01*
Y1219617D01*
X45355Y1175453D01*
X29994D01*
X26574Y1178873D01*
X14735D01*
X13805Y1179803D01*
X7677D01*
G01X335963Y1573797D02*
X330021Y1567855D01*
Y1417999D01*
X324528Y1412506D01*
X166772D01*
X152961Y1398695D01*
X107887D01*
X88219Y1379027D01*
Y1220831D01*
X44254Y1176866D01*
X30535D01*
X27226Y1180175D01*
X19116D01*
X15551Y1183740D01*
G01X312077Y1575871D02*
X327421Y1560527D01*
Y1419077D01*
X323450Y1415106D01*
X165694D01*
X153332Y1402744D01*
X97243D01*
X82601Y1388102D01*
Y1223627D01*
X51186Y1192212D01*
X31447D01*
X27459Y1196200D01*
X24444D01*
X17219Y1203425D01*
X7677D01*
G01X33267D02*
X23904D01*
X21686Y1205643D01*
Y1208254D01*
X24299Y1210867D01*
X26107D01*
X28217Y1212977D01*
Y1228576D01*
X31456Y1231815D01*
X61263D01*
X74801Y1245353D01*
Y1463829D01*
X106654Y1495682D01*
Y1723359D01*
X120304Y1737009D01*
X150309D01*
G01X25393Y1223110D02*
Y1224189D01*
X22590Y1226992D01*
Y1232116D01*
X24600Y1234126D01*
X28016D01*
X31683Y1237793D01*
X39394D01*
X40198Y1236989D01*
X49943D01*
X63815Y1250861D01*
Y1263898D01*
X73501Y1273584D01*
Y1465510D01*
X105354Y1497363D01*
Y1724518D01*
X119697Y1738861D01*
X144878D01*
G01X49441Y1238962D02*
X40524D01*
X39859Y1239627D01*
X31532D01*
X27789Y1235884D01*
X24123D01*
X20983Y1232744D01*
Y1219646D01*
X25393Y1215236D01*
G01X344402Y1911123D02*
X335828Y1902549D01*
Y1838379D01*
X330783Y1833334D01*
Y1769294D01*
X319726Y1758237D01*
X169419D01*
X153093Y1741911D01*
X117648D01*
X99537Y1723800D01*
Y1495645D01*
X58052Y1454160D01*
Y1326887D01*
X64990Y1319949D01*
Y1275940D01*
X34775Y1245724D01*
X32060D01*
X28430Y1242094D01*
X18787D01*
X15551Y1238858D01*
G01X345537Y1916558D02*
X334528Y1905549D01*
Y1838918D01*
X329483Y1833873D01*
Y1769833D01*
X319187Y1759537D01*
X168880D01*
X152554Y1743211D01*
X116599D01*
X98102Y1724714D01*
Y1496172D01*
X56296Y1454366D01*
Y1277872D01*
X50226Y1271802D01*
Y1263470D01*
X33817Y1247061D01*
X30951D01*
X27741Y1243851D01*
X17695D01*
X16639Y1242795D01*
X7677D01*
G01X15551Y1254606D02*
X18483Y1257538D01*
X28197D01*
X32101Y1261442D01*
X37387D01*
X52197Y1276252D01*
Y1454287D01*
X95439Y1497529D01*
Y1725729D01*
X114544Y1744834D01*
X152338D01*
X168341Y1760837D01*
X318648D01*
X328133Y1770322D01*
Y1834363D01*
X333228Y1839458D01*
Y1912073D01*
X340336Y1919181D01*
Y1922409D01*
G01X332399Y1926787D02*
Y1917488D01*
X331928Y1917017D01*
Y1839997D01*
X326833Y1834902D01*
Y1770861D01*
X318109Y1762137D01*
X167802D01*
X151850Y1746185D01*
X112217D01*
X92544Y1726512D01*
Y1498699D01*
X50603Y1456758D01*
Y1277173D01*
X42866Y1269436D01*
X31687D01*
X28041Y1265790D01*
X18861D01*
X15551Y1262480D01*
G01X45056Y1718480D02*
X91081Y1672455D01*
Y1499194D01*
X49151Y1457264D01*
Y1278347D01*
X41540Y1270736D01*
X31004D01*
X27769Y1267501D01*
X18404D01*
X15551Y1270354D01*
G01X45581Y1278420D02*
X31038D01*
X26486Y1282972D01*
X22749D01*
X19619Y1286102D01*
X15551D01*
G01X45350Y1299697D02*
X42144Y1302903D01*
X30686D01*
X28979Y1304610D01*
X21149D01*
X18389Y1301850D01*
X15551D01*
G01X45267Y1294203D02*
X44593Y1294877D01*
X31219D01*
X28183Y1297913D01*
X7677D01*
G01X15551Y1333346D02*
X19028Y1329869D01*
X27921D01*
X30782Y1332730D01*
X40093D01*
X46980Y1325843D01*
G01X7677Y1321535D02*
X28039D01*
X31173Y1318401D01*
X44422D01*
X46980Y1315843D01*
G01X7677Y1353031D02*
X13533D01*
X14180Y1353678D01*
X28388D01*
X34310Y1347756D01*
X45067D01*
X46980Y1345843D01*
G01X15551Y1349094D02*
X18597Y1352140D01*
X27970D01*
X34818Y1345292D01*
X42531D01*
X46980Y1340843D01*
G01X348289Y50863D02*
Y56952D01*
X338117Y67124D01*
Y194399D01*
X333974Y198542D01*
Y212639D01*
X326408Y220205D01*
X321296D01*
X301945Y239556D01*
Y254857D01*
X208638Y348164D01*
X116376D01*
X95563Y368977D01*
Y403901D01*
X102773Y411111D01*
Y422164D01*
X105040Y424431D01*
Y427668D01*
X102211Y430497D01*
Y666562D01*
X104710Y669061D01*
Y676136D01*
X69008Y711838D01*
Y778232D01*
X42755Y804485D01*
Y876928D01*
X35153Y884530D01*
X33263D01*
G01X25389Y888467D02*
X32350Y881506D01*
X35959D01*
X41453Y876012D01*
Y803947D01*
X67301Y778099D01*
Y711706D01*
X100819Y678188D01*
Y429968D01*
X103740Y427047D01*
Y424970D01*
X101473Y422703D01*
Y411650D01*
X94088Y404265D01*
Y368037D01*
X115668Y346457D01*
X207930D01*
X300238Y254149D01*
Y238848D01*
X320299Y218787D01*
X325987D01*
X332674Y212100D01*
Y198003D01*
X336817Y193860D01*
Y66302D01*
X345089Y58030D01*
Y56190D01*
G01X338227Y61559D02*
X335517Y64269D01*
Y193321D01*
X331374Y197464D01*
Y210967D01*
X324932Y217409D01*
X319357D01*
X298598Y238168D01*
Y253469D01*
X207250Y344817D01*
X114643D01*
X92621Y366839D01*
Y405298D01*
X100173Y412850D01*
Y424640D01*
X99216Y425597D01*
Y677952D01*
X65784Y711384D01*
Y777777D01*
X40105Y803456D01*
Y875257D01*
X35271Y880091D01*
X25891D01*
X25389Y880593D01*
G01X340373Y51579D02*
Y56290D01*
X334217Y62446D01*
Y192782D01*
X330074Y196925D01*
Y209589D01*
X323679Y215984D01*
X318622D01*
X297071Y237535D01*
Y252836D01*
X206617Y343290D01*
X112613D01*
X91321Y364582D01*
Y406626D01*
X98873Y414178D01*
Y424034D01*
X97857Y425050D01*
Y677472D01*
X64238Y711091D01*
Y777483D01*
X38713Y803008D01*
Y871206D01*
X33263Y876656D01*
G01X331403Y51409D02*
Y191918D01*
X327474Y195847D01*
Y207745D01*
X322733Y212486D01*
X316739D01*
X293267Y235958D01*
Y252602D01*
X206383Y339486D01*
X111114D01*
X88721Y361879D01*
Y407704D01*
X96273Y415256D01*
Y422956D01*
X95257Y423972D01*
Y662387D01*
X61371Y696273D01*
Y776672D01*
X36019Y802024D01*
Y866026D01*
X33263Y868782D01*
G01X25389Y864845D02*
Y866081D01*
X31406Y872098D01*
X34619D01*
X37366Y869351D01*
Y802516D01*
X62833Y777049D01*
Y696651D01*
X96557Y662927D01*
Y424511D01*
X97573Y423495D01*
Y414717D01*
X90021Y407165D01*
Y363146D01*
X111811Y341356D01*
X206635D01*
X295137Y252854D01*
Y236733D01*
X317848Y214022D01*
X323037D01*
X328774Y208285D01*
Y196386D01*
X332917Y192243D01*
Y61838D01*
X333889Y60866D01*
Y56021D01*
G01X139920Y58071D02*
X139908D01*
X130072Y67907D01*
Y79597D01*
X127305Y82364D01*
X116772D01*
X96165Y102971D01*
Y350659D01*
X87421Y359403D01*
Y408243D01*
X94973Y415795D01*
Y418461D01*
X92565Y420869D01*
Y661401D01*
X57773Y696193D01*
Y776591D01*
X41280Y793084D01*
X31475D01*
X28579Y795980D01*
Y845907D01*
X25389Y849097D01*
G01X94347Y421562D02*
X93957Y421952D01*
Y661848D01*
X59448Y696357D01*
Y776756D01*
X41500Y794704D01*
X32343D01*
X30199Y796848D01*
Y842096D01*
X33263Y845160D01*
G01X25389Y919963D02*
X34196D01*
X36074Y921841D01*
X61035D01*
X76417Y906459D01*
Y901205D01*
X96463Y881159D01*
Y789389D01*
X82575Y775501D01*
Y722093D01*
X111210Y693458D01*
X230625D01*
X305142Y618941D01*
Y580736D01*
X319966Y565912D01*
X321306D01*
X328223Y558995D01*
Y541000D01*
X331204Y538019D01*
Y453318D01*
X323313Y445427D01*
Y418313D01*
G01X33263Y916026D02*
X37198Y919961D01*
X61048D01*
X75097Y905912D01*
Y900595D01*
X95116Y880576D01*
Y790649D01*
X80330Y775863D01*
Y722499D01*
X110691Y692138D01*
X230078D01*
X303822Y618394D01*
Y580189D01*
X319419Y564592D01*
X320759D01*
X326903Y558448D01*
Y540453D01*
X329884Y537472D01*
Y453865D01*
X320980Y444961D01*
Y423225D01*
G01X326196Y413982D02*
Y446448D01*
X332520Y452772D01*
Y538565D01*
X329539Y541546D01*
Y559541D01*
X321852Y567228D01*
X320512D01*
X306458Y581282D01*
Y619487D01*
X231171Y694774D01*
X111734D01*
X84192Y722316D01*
Y774782D01*
X97959Y788549D01*
Y881639D01*
X77733Y901865D01*
Y907616D01*
X61449Y923900D01*
X33263D01*
G01X335522Y404033D02*
X331786Y407769D01*
Y448192D01*
X335239Y451645D01*
Y539692D01*
X332258Y542673D01*
Y560668D01*
X322979Y569947D01*
X321639D01*
X309177Y582409D01*
Y620614D01*
X232298Y697493D01*
X112694D01*
X87785Y722402D01*
Y773569D01*
X100802Y786586D01*
Y883571D01*
X81070Y903303D01*
Y908923D01*
X54282Y935711D01*
X25389D01*
G01X342097Y401684D02*
X333834Y409947D01*
Y448326D01*
X336592Y451084D01*
Y540253D01*
X333611Y543234D01*
Y561229D01*
X323540Y571300D01*
X322200D01*
X310530Y582970D01*
Y621175D01*
X232859Y698846D01*
X113180D01*
X89402Y722624D01*
Y773120D01*
X102239Y785957D01*
Y884421D01*
X82687Y903973D01*
Y909593D01*
X52632Y939648D01*
X33263D01*
G01X328950Y409216D02*
Y447271D01*
X333885Y452206D01*
Y539131D01*
X330904Y542112D01*
Y560107D01*
X322418Y568593D01*
X321078D01*
X307823Y581848D01*
Y620053D01*
X231737Y696139D01*
X112209D01*
X85899Y722449D01*
Y773929D01*
X99425Y787455D01*
Y882824D01*
X79363Y902886D01*
Y908292D01*
X59818Y927837D01*
X25389D01*
G01X331568Y752967D02*
Y791869D01*
X335094Y795395D01*
Y847696D01*
X329738Y853052D01*
Y911721D01*
X311815Y929644D01*
Y969652D01*
X256033Y1025434D01*
X186346D01*
X182041Y1029739D01*
X170503D01*
X168476Y1031766D01*
X67013D01*
X46362Y1011115D01*
Y1006544D01*
X34584Y994766D01*
X33263D01*
G01X25389Y975081D02*
X29996Y979688D01*
Y987024D01*
X48050Y1005078D01*
Y1010963D01*
X67165Y1030078D01*
X167999D01*
X169914Y1028163D01*
X180727D01*
X184859Y1024031D01*
X255597D01*
X310127Y969501D01*
Y928944D01*
X328281Y910790D01*
Y852540D01*
X333486Y847335D01*
Y796416D01*
X329336Y792266D01*
Y762693D01*
G01X25389Y990829D02*
X29731Y995171D01*
Y995833D01*
X31694Y997796D01*
X34927D01*
X44898Y1007767D01*
Y1011491D01*
X67070Y1033663D01*
X184070D01*
X190837Y1026896D01*
X256410D01*
X313279Y970027D01*
Y930251D01*
X331202Y912328D01*
Y853794D01*
X336558Y848438D01*
Y794252D01*
X334010Y791704D01*
Y758588D01*
G01X33263Y979018D02*
Y987722D01*
X49866Y1004325D01*
Y1010939D01*
X67189Y1028262D01*
X167214D01*
X168731Y1026745D01*
X178901D01*
X182969Y1022677D01*
X255112D01*
X308311Y969477D01*
Y928036D01*
X326518Y909829D01*
Y851862D01*
X331819Y846561D01*
Y797624D01*
X327524Y793329D01*
Y758020D01*
G01X33263Y1002640D02*
X40539Y1009916D01*
Y1013292D01*
X63661Y1036414D01*
X250837D01*
X316030Y971219D01*
Y931392D01*
X333953Y913469D01*
Y855258D01*
X339231Y849980D01*
Y756687D01*
X344109Y751809D01*
G01X25389Y998703D02*
X29339D01*
X30361Y999725D01*
X34496D01*
X42944Y1008173D01*
Y1012342D01*
X65632Y1035030D01*
X185617D01*
X191985Y1028662D01*
X256484D01*
X314646Y970500D01*
Y930818D01*
X332569Y912895D01*
Y854707D01*
X337925Y849351D01*
Y753946D01*
X339012Y752859D01*
G01X25393Y1097125D02*
X34335Y1088183D01*
X48899D01*
X83820Y1053262D01*
X309678D01*
G01X25393Y1089251D02*
X32689Y1081955D01*
X41915D01*
X74220Y1049650D01*
X322110D01*
X324246Y1051786D01*
G01X33267Y1077440D02*
X42656D01*
X73281Y1046815D01*
X344549D01*
X345578Y1047844D01*
G01X25393Y1081377D02*
X30119D01*
X31146Y1080350D01*
X41603D01*
X73825Y1048128D01*
X334902D01*
X335677Y1048903D01*
G01X33267Y1101062D02*
X43776Y1090553D01*
X52261D01*
X82763Y1060051D01*
G01X33267Y1085314D02*
X49628D01*
X83992Y1050950D01*
X315492D01*
X317592Y1053050D01*
G01X33267Y1148306D02*
X38212D01*
X47760Y1138758D01*
X82286D01*
X94766Y1151238D01*
Y1374245D01*
X112449Y1391928D01*
X165692D01*
X168425Y1394661D01*
Y1394663D01*
X176083Y1402321D01*
G01X25393Y1136496D02*
X32445Y1143548D01*
X38022D01*
X44730Y1136840D01*
X82858D01*
X96066Y1150048D01*
Y1373255D01*
X113358Y1390547D01*
X170204D01*
X179296Y1399639D01*
X320523D01*
X323116Y1402232D01*
X333218D01*
X334646Y1400804D01*
G01X25393Y1144370D02*
X32908Y1151885D01*
X36753D01*
X48381Y1140257D01*
X81665D01*
X93466Y1152058D01*
Y1374917D01*
X111937Y1393388D01*
X162395D01*
X170351Y1401344D01*
G01X33267Y1140432D02*
X38297D01*
X43251Y1135478D01*
X83452D01*
X97366Y1149392D01*
Y1372273D01*
X114318Y1389225D01*
X171594D01*
X180708Y1398339D01*
X321062D01*
X323655Y1400932D01*
X327757D01*
X330350Y1398339D01*
X340799D01*
X344130Y1401670D01*
G01X25393Y1160118D02*
X37731D01*
X54725Y1143124D01*
X80477D01*
X90819Y1153466D01*
Y1376464D01*
X110400Y1396045D01*
X155129D01*
X156364Y1397280D01*
X156450D01*
X158618Y1399448D01*
G01X33267Y1156180D02*
X39642D01*
X54131Y1141691D01*
X81071D01*
X92166Y1152786D01*
Y1375734D01*
X111155Y1394723D01*
X158534D01*
X164037Y1400226D01*
G01X33267Y1195551D02*
X43419D01*
X81301Y1233433D01*
Y1460051D01*
X113923Y1492673D01*
Y1720524D01*
X122691Y1729292D01*
X166635D01*
X173394Y1736051D01*
G01X25393Y1199488D02*
X44432D01*
X80001Y1235057D01*
Y1460907D01*
X112582Y1493488D01*
Y1721351D01*
X121823Y1730592D01*
X163472D01*
X165782Y1732902D01*
G01X156183Y1735240D02*
X120572D01*
X108131Y1722799D01*
Y1495004D01*
X76101Y1462974D01*
Y1243936D01*
X62272Y1230107D01*
X32059D01*
X29824Y1227872D01*
Y1209862D01*
X27324Y1207362D01*
X25393D01*
G01X33267Y1227047D02*
X66741D01*
X77401Y1237707D01*
Y1462387D01*
X109588Y1494574D01*
Y1722413D01*
X120641Y1733466D01*
X159104D01*
X163257Y1737619D01*
G01X33267Y1219173D02*
X61021D01*
X78701Y1236853D01*
Y1461533D01*
X111111Y1493943D01*
Y1721782D01*
X121495Y1732166D01*
X161109D01*
X168151Y1739208D01*
G01X45413Y1283724D02*
X39582D01*
X33267Y1290039D01*
G01X45281Y1310893D02*
X42513Y1313661D01*
X33267D01*
G01Y1305787D02*
X45244D01*
G01Y1289067D02*
X41259Y1293052D01*
X30602D01*
X29678Y1293976D01*
X25393D01*
G01Y1325472D02*
X42351D01*
X46980Y1320843D01*
G01Y1330843D02*
X40540Y1337283D01*
X33267D01*
G01X114498Y396207D02*
Y686491D01*
X78882Y722107D01*
Y776435D01*
X93634Y791187D01*
Y870377D01*
X75156Y888855D01*
Y893459D01*
X70865Y897750D01*
G01X357165Y1784705D02*
X353177D01*
X348511Y1789371D01*
X337181D01*
X332325Y1784515D01*
Y1768626D01*
X320297Y1756598D01*
X169881D01*
X153894Y1740611D01*
X119223D01*
X103782Y1725170D01*
Y1497724D01*
X59661Y1453603D01*
Y1328204D01*
X67100Y1320765D01*
Y1311476D01*
X69568Y1309008D01*
Y1272631D01*
X61708Y1264771D01*
Y1251229D01*
X49441Y1238962D01*
G01X61866Y1342104D02*
Y1336677D01*
X70340Y1328203D01*
G01X82763Y1060051D02*
X87340Y1055474D01*
X314654D01*
X331376Y1072196D01*
Y1089549D01*
X335208Y1093381D01*
X353546D01*
X362165Y1084762D01*
Y1079705D01*
G01X362236Y324983D02*
Y331983D01*
X358479Y335740D01*
Y342881D01*
X347216Y354144D01*
X308012D01*
X302744Y359412D01*
X123999D01*
X119920Y363491D01*
Y366102D01*
G01X100719Y1346065D02*
X98755Y1344101D01*
Y1314774D01*
X100719Y1312810D01*
G01Y1324810D02*
X104483Y1328574D01*
Y1376800D01*
X115168Y1387485D01*
X172848D01*
X182402Y1397039D01*
X354193D01*
X373407Y1377825D01*
Y1366894D01*
X374681Y1365620D01*
G01X337165Y1784705D02*
X333625Y1781165D01*
Y1767999D01*
X320924Y1755298D01*
X170420D01*
X153983Y1738861D01*
X144878D01*
G01X158618Y1399448D02*
X169076Y1409906D01*
X326436D01*
X332815Y1416285D01*
Y1437467D01*
X335746Y1440398D01*
X357126D01*
X362165Y1435359D01*
Y1429705D01*
G01X164037Y1400226D02*
X172210Y1408399D01*
X326769D01*
X334115Y1415745D01*
Y1436927D01*
X335904Y1438716D01*
X353154D01*
X357165Y1434705D01*
G01X342165Y1779705D02*
Y1774833D01*
X345745Y1771253D01*
Y1768541D01*
X342386Y1765182D01*
X340462D01*
X324628Y1749348D01*
X174986D01*
X163257Y1737619D01*
G01X337165Y1774705D02*
Y1769474D01*
X321519Y1753828D01*
X173303D01*
X156484Y1737009D01*
X150309D01*
G01X362165Y1779705D02*
X357511D01*
X347804Y1769998D01*
Y1767004D01*
X328767Y1747967D01*
X176910D01*
X168151Y1739208D01*
G01X165782Y1732902D02*
X179516Y1746636D01*
X339096D01*
X362165Y1769705D01*
G01X165782Y1732902D02*
Y1732903D01*
G01X342165Y1769705D02*
Y1768819D01*
X324453Y1751107D01*
X173049D01*
X157182Y1735240D01*
X156183D01*
G01X342165Y1419705D02*
X327633Y1405173D01*
X178935D01*
X176083Y1402321D01*
G01X170351Y1401344D02*
Y1401324D01*
G01X337165Y1424705D02*
Y1416956D01*
X327201Y1406992D01*
X175999D01*
X170351Y1401344D01*
G01X173394Y1736051D02*
X182459Y1745116D01*
X342064D01*
X365899Y1768951D01*
Y1770836D01*
X362030Y1774705D01*
X357165D01*
G01X308057Y248863D02*
X321510Y235410D01*
Y231579D01*
X323588Y229501D01*
X328414D01*
X340130Y217785D01*
Y213672D01*
X340978Y212824D01*
Y205934D01*
X342186Y204726D01*
X342165Y204705D01*
G01X337165Y209705D02*
Y217329D01*
X326490Y228004D01*
X319273D01*
X306267Y241010D01*
G01X309678Y1053262D02*
X314366D01*
X332990Y1071886D01*
Y1088880D01*
X335600Y1091490D01*
X350380D01*
X357165Y1084705D01*
G01X347165Y1609705D02*
X341860D01*
X331394Y1599239D01*
Y1595188D01*
X312077Y1575871D01*
G01X337165Y24705D02*
Y30117D01*
X340373Y33325D01*
Y51579D01*
G01X331403Y51409D02*
Y22773D01*
X338999Y15177D01*
X357637D01*
X362165Y19705D01*
G01X333889Y56021D02*
Y22656D01*
X339992Y16553D01*
X353709D01*
X357165Y20009D01*
Y24705D01*
G01X342165Y19705D02*
Y25030D01*
X345685Y28550D01*
Y31569D01*
X342731Y34523D01*
Y57055D01*
X338227Y61559D01*
G01X314940Y252084D02*
X344399Y222625D01*
Y215788D01*
X347165Y213022D01*
Y209705D01*
G01X320961Y250105D02*
X346344Y224722D01*
Y216399D01*
X350309Y212434D01*
Y207982D01*
X348819Y206492D01*
Y201359D01*
X347165Y199705D01*
G01X314940Y252083D02*
Y252084D01*
G01X362165Y369705D02*
X356430Y363970D01*
X339253D01*
X329791Y373432D01*
Y397570D01*
X323313Y404048D01*
Y418313D01*
G01X357165Y374705D02*
X362309D01*
X366517Y370497D01*
Y367475D01*
X361692Y362650D01*
X338706D01*
X328003Y373353D01*
Y396242D01*
X320980Y403265D01*
Y423225D01*
G01X326196Y413982D02*
Y405259D01*
X332044Y399411D01*
Y384882D01*
X337167Y379759D01*
Y374707D01*
X337165Y374705D01*
G01X335522Y404033D02*
X354850Y384705D01*
X357165D01*
G01X342165Y369705D02*
X342167Y369707D01*
Y375104D01*
X345215Y378152D01*
Y382080D01*
X343200Y384095D01*
Y391909D01*
X328950Y406159D01*
Y409216D01*
G01X319305Y582111D02*
X340711Y560705D01*
Y558500D01*
X338462Y556251D01*
Y553326D01*
X342083Y549705D01*
X347166D01*
G01X320380Y576491D02*
X337166Y559705D01*
G01X317724Y588250D02*
Y586292D01*
X342166Y561850D01*
Y554705D01*
G01X347166Y559705D02*
Y561852D01*
X321742Y587276D01*
Y599041D01*
G01X331568Y752967D02*
Y723878D01*
X335741Y719705D01*
X342166D01*
G01X357166Y724705D02*
Y718067D01*
X355198Y716099D01*
X337099D01*
X329336Y723862D01*
Y762693D01*
G01X337166Y724705D02*
X334010Y727861D01*
Y758588D01*
G01X362166Y719705D02*
X356893Y714432D01*
X336408D01*
X327524Y723316D01*
Y758020D01*
G01X339012Y752859D02*
X357166Y734705D01*
G01X321425Y951577D02*
X320372Y950524D01*
Y928963D01*
X337165Y912170D01*
Y909705D01*
G01X324098Y946104D02*
Y938250D01*
X321888Y936040D01*
Y929347D01*
X342130Y909105D01*
Y904740D01*
X342165Y904705D01*
G01X347165Y899705D02*
X347130Y899740D01*
Y905078D01*
X343752Y908456D01*
Y910600D01*
X326646Y927706D01*
Y939788D01*
G01X328583Y933262D02*
Y928287D01*
X347165Y909705D01*
G01X324246Y1051786D02*
X342165Y1069705D01*
G01X362165D02*
X356479D01*
X335677Y1048903D01*
G01D02*
Y1048904D01*
G01X337165Y1074705D02*
Y1072623D01*
X317592Y1053050D01*
G01X337165Y1259705D02*
Y1266899D01*
X321978Y1282086D01*
G01X342165Y1254705D02*
Y1257901D01*
X340678Y1259388D01*
Y1266221D01*
X327452Y1279447D01*
G01X347165Y1249705D02*
Y1255190D01*
X350447Y1258472D01*
Y1266706D01*
X327932Y1289221D01*
G01X347165Y1259705D02*
Y1266470D01*
X329619Y1284016D01*
G01X334646Y1400804D02*
X338426D01*
X357165Y1419543D01*
Y1424705D01*
G01X323720Y1570924D02*
X347165Y1594369D01*
Y1599705D01*
G01X333474Y1566686D02*
X358639Y1591851D01*
Y1595862D01*
X360282Y1597505D01*
Y1601631D01*
X358334Y1603579D01*
Y1605911D01*
X360224Y1607801D01*
Y1611776D01*
X358701Y1613299D01*
X340759D01*
X337165Y1609705D01*
G01X335963Y1573797D02*
X355505Y1593339D01*
Y1596703D01*
X353900Y1598308D01*
Y1601326D01*
X356155Y1603581D01*
Y1605873D01*
X354054Y1607974D01*
X350805D01*
X349353Y1606522D01*
X343982D01*
X342165Y1604705D01*
G01X347165Y1959705D02*
X342316D01*
X332399Y1949788D01*
Y1926787D01*
G01X344402Y1911123D02*
X364941Y1931662D01*
Y1940969D01*
X365937Y1941965D01*
Y1956711D01*
X358621Y1964027D01*
X341487D01*
X337165Y1959705D01*
G01X362165Y29705D02*
X357371D01*
X345089Y41987D01*
Y56190D01*
G01X348289Y50863D02*
Y43581D01*
X357165Y34705D01*
G01X362165Y379705D02*
Y384045D01*
X358140Y388070D01*
X355711D01*
X342097Y401684D01*
G01X344109Y751809D02*
Y750127D01*
X354494Y739742D01*
X356443D01*
X362166Y734019D01*
Y729705D01*
G01X357165Y1074705D02*
X362525D01*
X365595Y1071635D01*
Y1067861D01*
X345578Y1047844D01*
G01X344130Y1401670D02*
X362165Y1419705D01*
G01X345537Y1916558D02*
X355429Y1926450D01*
Y1946553D01*
X354093Y1947889D01*
Y1951248D01*
X355965Y1953120D01*
Y1955986D01*
X353366Y1958585D01*
X350883D01*
X347003Y1954705D01*
X342165D01*
G01X347165Y1949705D02*
Y1929238D01*
X340336Y1922409D01*
M02*
